FILE_TYPE = MACRO_DRAWING;
SET COLOR_WIRE YELLOW;
SET COLOR_PROP ORANGE;
SET COLOR_DOT WHITE;
SET COLOR_ARC YELLOW;
SET COLOR_BODY GREEN;
SET COLOR_NOTE PURPLE;
SET PROP_DISPLAY VALUE;
SET PAGE_NUMBER P170;
FORCEADD OFFPAGE..1
(-7825 1400);
FORCEPROP 2 LAST $XR5 199 
J 0
(-8707 1400);
DISPLAY 0.638298 (-8707 1400);
PAINT MONO (-8707 1400);
FORCEPROP 2 LAST $XR4 198 
J 0
(-8587 1400);
DISPLAY 0.638298 (-8587 1400);
PAINT MONO (-8587 1400);
FORCEPROP 2 LAST $XR3 196 
J 0
(-8467 1400);
DISPLAY 0.638298 (-8467 1400);
PAINT MONO (-8467 1400);
FORCEPROP 2 LAST $XR2 195 
J 0
(-8347 1400);
DISPLAY 0.638298 (-8347 1400);
PAINT MONO (-8347 1400);
FORCEPROP 2 LAST $XR1 194 
J 0
(-8227 1400);
DISPLAY 0.638298 (-8227 1400);
PAINT MONO (-8227 1400);
FORCEPROP 2 LAST $XR0 193 
J 0
(-8107 1400);
DISPLAY 0.638298 (-8107 1400);
PAINT MONO (-8107 1400);
FORCEPROP 2 LAST CDS_LIB standard
J 0
(-7825 1400);
DISPLAY INVISIBLE (-7825 1400);
FORCEPROP 1 LAST OFFPAGE TRUE
J 0
(-7500 1275);
DISPLAY 0.872340 (-7500 1275);
PAINT GREEN (-7500 1275);
DISPLAY INVISIBLE (-7500 1275);
FORCEPROP 1 LAST COMMENT_BODY TRUE
J 0
(-7700 1300);
DISPLAY 0.872340 (-7700 1300);
PAINT GREEN (-7700 1300);
DISPLAY INVISIBLE (-7700 1300);
FORCEPROP 2 LAST PATH I1
J 0
(-8100 1450);
DISPLAY 0.680851 (-8100 1450);
DISPLAY INVISIBLE (-8100 1450);
FORCEADD OFFPAGE..2
R 2
(-6900 1000);
FORCEPROP 2 LAST $XR3 193 
J 0
(-7395 964);
DISPLAY 0.638298 (-7395 964);
PAINT MONO (-7395 964);
FORCEPROP 2 LAST $XR2 196 
J 0
(-7275 964);
DISPLAY 0.638298 (-7275 964);
PAINT MONO (-7275 964);
FORCEPROP 2 LAST $XR1 195 
J 0
(-7155 964);
DISPLAY 0.638298 (-7155 964);
PAINT MONO (-7155 964);
FORCEPROP 2 LAST $XR0 194 
J 0
(-7155 1000);
DISPLAY 0.638298 (-7155 1000);
PAINT MONO (-7155 1000);
FORCEPROP 2 LAST CDS_LIB standard
J 0
(-6900 1000);
DISPLAY INVISIBLE (-6900 1000);
FORCEPROP 1 LAST OFFPAGE TRUE
J 2
(-7225 875);
DISPLAY 0.872340 (-7225 875);
PAINT GREEN (-7225 875);
DISPLAY INVISIBLE (-7225 875);
FORCEPROP 1 LAST COMMENT_BODY TRUE
J 2
(-6855 905);
DISPLAY 0.872340 (-6855 905);
PAINT GREEN (-6855 905);
DISPLAY INVISIBLE (-6855 905);
FORCEPROP 2 LAST PATH I10
J 0
(-7150 1050);
DISPLAY 0.680851 (-7150 1050);
DISPLAY INVISIBLE (-7150 1050);
FORCEADD Q_RES..1
(-6950 1200);
FORCEPROP 1 LAST LOCATION PR347
J 0
(-7000 1250);
DISPLAY 0.489362 (-7000 1250);
PAINT SKYBLUE (-7000 1250);
FORCEPROP 0 LAST $SEC 1
J 0
(-6950 1275);
DISPLAY 0.680851 (-6950 1275);
PAINT MONO (-6950 1275);
DISPLAY INVISIBLE (-6950 1275);
FORCEPROP 0 LAST CDS_SEC 1
J 0
(-6950 1275);
DISPLAY 1.021277 (-6950 1275);
DISPLAY INVISIBLE (-6950 1275);
FORCEPROP 1 LASTPIN (-7050 1200) $PN 1
J 0
(-7038 1212);
DISPLAY 0.489362 (-7038 1212);
PAINT MONO (-7038 1212);
FORCEPROP 1 LASTPIN (-6850 1200) $PN 2
J 0
(-6888 1212);
DISPLAY 0.489362 (-6888 1212);
PAINT MONO (-6888 1212);
FORCEPROP 1 LAST PACK_TYPE 0402LF
J 0
(-6850 1150);
DISPLAY 0.489362 (-6850 1150);
PAINT SKYBLUE (-6850 1150);
FORCEPROP 1 LAST VALUE 8.87K
J 2
(-7075 1225);
DISPLAY 0.489362 (-7075 1225);
PAINT SKYBLUE (-7075 1225);
FORCEPROP 1 LAST TOLERANCE 1%
J 0
(-6825 1225);
DISPLAY 0.489362 (-6825 1225);
PAINT SKYBLUE (-6825 1225);
FORCEPROP 1 LAST MATERIAL EMPTY
J 0
(-7250 1100);
DISPLAY 0.489362 (-7250 1100);
PAINT RED (-7250 1100);
FORCEPROP 1 LAST WATTAGE 1/16W
J 0
(-6850 1100);
DISPLAY 0.489362 (-6850 1100);
PAINT SKYBLUE (-6850 1100);
FORCEPROP 2 LAST CDS_LIB pure_quanta
J 0
(-6950 1200);
DISPLAY INVISIBLE (-6950 1200);
FORCEPROP 1 LAST PATH I11
J 0
(-7000 1350);
DISPLAY 0.978723 (-7000 1350);
PAINT WHITE (-7000 1350);
DISPLAY INVISIBLE (-7000 1350);
FORCEPROP 1 LAST PART_NUMBER CS28872FB01
J 0
(-7250 1150);
DISPLAY 0.489362 (-7250 1150);
PAINT SKYBLUE (-7250 1150);
DISPLAY INVISIBLE (-7250 1150);
FORCEADD Q_RES..2
(-7250 2400);
FORCEPROP 1 LAST LOCATION PR345
J 0
(-7205 2525);
DISPLAY 0.489362 (-7205 2525);
PAINT SKYBLUE (-7205 2525);
FORCEPROP 0 LAST $SEC 1
J 0
(-7200 2575);
DISPLAY 0.680851 (-7200 2575);
PAINT MONO (-7200 2575);
DISPLAY INVISIBLE (-7200 2575);
FORCEPROP 0 LAST CDS_SEC 1
J 0
(-7200 2575);
DISPLAY 1.021277 (-7200 2575);
DISPLAY INVISIBLE (-7200 2575);
FORCEPROP 1 LASTPIN (-7250 2500) $PN 1
J 0
(-7245 2462);
DISPLAY 0.489362 (-7245 2462);
PAINT MONO (-7245 2462);
FORCEPROP 1 LASTPIN (-7250 2300) $PN 2
J 0
(-7245 2310);
DISPLAY 0.489362 (-7245 2310);
PAINT MONO (-7245 2310);
FORCEPROP 1 LAST PACK_TYPE 0402LF
J 0
(-7200 2225);
DISPLAY 0.489362 (-7200 2225);
PAINT SKYBLUE (-7200 2225);
FORCEPROP 1 LAST VALUE 2.2
J 0
(-7200 2475);
DISPLAY 0.489362 (-7200 2475);
PAINT SKYBLUE (-7200 2475);
FORCEPROP 1 LAST TOLERANCE 1%
J 0
(-7200 2425);
DISPLAY 0.489362 (-7200 2425);
PAINT SKYBLUE (-7200 2425);
FORCEPROP 1 LAST MATERIAL CHIP
J 0
(-7200 2325);
DISPLAY 0.489362 (-7200 2325);
PAINT SKYBLUE (-7200 2325);
FORCEPROP 1 LAST WATTAGE 1/16W
J 0
(-7200 2375);
DISPLAY 0.489362 (-7200 2375);
PAINT SKYBLUE (-7200 2375);
FORCEPROP 2 LAST CDS_LIB pure_quanta
J 0
(-7250 2400);
DISPLAY INVISIBLE (-7250 2400);
FORCEPROP 1 LAST PATH I12
J 0
(-7200 2575);
DISPLAY 0.978723 (-7200 2575);
PAINT WHITE (-7200 2575);
DISPLAY INVISIBLE (-7200 2575);
FORCEPROP 1 LAST PART_NUMBER CS-2202FB01
J 0
(-7200 2275);
DISPLAY 0.489362 (-7200 2275);
PAINT SKYBLUE (-7200 2275);
DISPLAY INVISIBLE (-7200 2275);
FORCEADD VCC_CORE..1
(-7250 2800);
FORCEPROP 3 LASTPIN (-7250 2750) SIG_NAME PVDDCR_CPU0_P0_PVCC\g
J 0
(-7240 2760);
DISPLAY 0.659574 (-7240 2760);
PAINT MONO (-7240 2760);
DISPLAY INVISIBLE (-7240 2760);
FORCEPROP 1 LAST HDL_POWER PVDDCR_CPU0_P0_PVCC
J 1
(-7250 2850);
DISPLAY 0.489362 (-7250 2850);
PAINT GREEN (-7250 2850);
FORCEPROP 2 LAST CDS_LIB pure_quanta_power
J 0
(-7250 2800);
DISPLAY INVISIBLE (-7250 2800);
FORCEPROP 1 LAST PATH I13
J 0
(-7200 2825);
DISPLAY 0.872340 (-7200 2825);
PAINT AQUA (-7200 2825);
DISPLAY INVISIBLE (-7200 2825);
FORCEADD UNIVERSAL_GND..1
(-6900 2150);
FORCEPROP 3 LASTPIN (-6900 2200) SIG_NAME GND\g
J 0
(-6890 2210);
DISPLAY 0.659574 (-6890 2210);
PAINT MONO (-6890 2210);
DISPLAY INVISIBLE (-6890 2210);
FORCEPROP 2 LAST CDS_LIB pure_quanta_power
J 0
(-6900 2150);
DISPLAY INVISIBLE (-6900 2150);
FORCEPROP 1 LAST HDL_POWER GND
J 1
(-6875 2075);
DISPLAY 0.872340 (-6875 2075);
PAINT GREEN (-6875 2075);
DISPLAY INVISIBLE (-6875 2075);
FORCEPROP 1 LAST PATH I14
J 0
(-6825 2150);
DISPLAY 0.872340 (-6825 2150);
PAINT AQUA (-6825 2150);
DISPLAY INVISIBLE (-6825 2150);
FORCEADD Q_CAP..1
(-6900 2425);
FORCEPROP 1 LAST LOCATION PC549_C0P0_4
J 0
(-6850 2525);
DISPLAY 0.489362 (-6850 2525);
PAINT SKYBLUE (-6850 2525);
FORCEPROP 0 LAST $SEC 1
J 0
(-6850 2575);
DISPLAY 0.680851 (-6850 2575);
PAINT MONO (-6850 2575);
DISPLAY INVISIBLE (-6850 2575);
FORCEPROP 0 LAST CDS_SEC 1
J 0
(-6850 2575);
DISPLAY 1.021277 (-6850 2575);
DISPLAY INVISIBLE (-6850 2575);
FORCEPROP 1 LASTPIN (-6900 2525) $PN 1
J 0
(-6890 2505);
DISPLAY 0.489362 (-6890 2505);
PAINT MONO (-6890 2505);
FORCEPROP 1 LASTPIN (-6900 2325) $PN 2
J 0
(-6890 2305);
DISPLAY 0.489362 (-6890 2305);
PAINT MONO (-6890 2305);
FORCEPROP 1 LAST MATERIAL X6S
J 0
(-6850 2325);
DISPLAY 0.489362 (-6850 2325);
PAINT SKYBLUE (-6850 2325);
FORCEPROP 1 LAST VALUE 2.2UF
J 0
(-6850 2475);
DISPLAY 0.489362 (-6850 2475);
PAINT SKYBLUE (-6850 2475);
FORCEPROP 1 LAST VOLTAGE 10V
J 0
(-6850 2425);
DISPLAY 0.489362 (-6850 2425);
PAINT SKYBLUE (-6850 2425);
FORCEPROP 1 LAST PACK_TYPE C0402
J 0
(-6850 2225);
DISPLAY 0.489362 (-6850 2225);
PAINT SKYBLUE (-6850 2225);
FORCEPROP 1 LAST TOLERANCE 10%
J 0
(-6850 2375);
DISPLAY 0.489362 (-6850 2375);
PAINT SKYBLUE (-6850 2375);
FORCEPROP 2 LAST CDS_LIB pure_quanta
J 0
(-6900 2425);
DISPLAY INVISIBLE (-6900 2425);
FORCEPROP 1 LAST PATH I15
J 0
(-6850 2575);
DISPLAY 0.978723 (-6850 2575);
PAINT WHITE (-6850 2575);
DISPLAY INVISIBLE (-6850 2575);
FORCEPROP 1 LAST PART_NUMBER CH5222KEB01
J 0
(-6850 2275);
DISPLAY 0.489362 (-6850 2275);
PAINT SKYBLUE (-6850 2275);
DISPLAY INVISIBLE (-6850 2275);
FORCEADD UNIVERSAL_GND..1
(-5225 750);
FORCEPROP 3 LASTPIN (-5225 800) SIG_NAME GND\g
J 0
(-5215 810);
DISPLAY 0.659574 (-5215 810);
PAINT MONO (-5215 810);
DISPLAY INVISIBLE (-5215 810);
FORCEPROP 2 LAST CDS_LIB pure_quanta_power
J 0
(-5225 750);
DISPLAY INVISIBLE (-5225 750);
FORCEPROP 1 LAST HDL_POWER GND
J 1
(-5200 675);
DISPLAY 0.872340 (-5200 675);
PAINT GREEN (-5200 675);
DISPLAY INVISIBLE (-5200 675);
FORCEPROP 1 LAST PATH I16
J 0
(-5150 750);
DISPLAY 0.872340 (-5150 750);
PAINT AQUA (-5150 750);
DISPLAY INVISIBLE (-5150 750);
FORCEADD UNIVERSAL_GND..1
(-4300 650);
FORCEPROP 3 LASTPIN (-4300 700) SIG_NAME GND\g
J 0
(-4290 710);
DISPLAY 0.659574 (-4290 710);
PAINT MONO (-4290 710);
DISPLAY INVISIBLE (-4290 710);
FORCEPROP 2 LAST CDS_LIB pure_quanta_power
J 0
(-4300 650);
DISPLAY INVISIBLE (-4300 650);
FORCEPROP 1 LAST HDL_POWER GND
J 1
(-4275 575);
DISPLAY 0.872340 (-4275 575);
PAINT GREEN (-4275 575);
DISPLAY INVISIBLE (-4275 575);
FORCEPROP 1 LAST PATH I17
J 0
(-4225 650);
DISPLAY 0.872340 (-4225 650);
PAINT AQUA (-4225 650);
DISPLAY INVISIBLE (-4225 650);
FORCEADD Q_RES..2
(-4300 875);
FORCEPROP 1 LAST LOCATION PR499
J 0
(-4255 1000);
DISPLAY 0.489362 (-4255 1000);
PAINT SKYBLUE (-4255 1000);
FORCEPROP 0 LAST $SEC 1
J 0
(-4250 1050);
DISPLAY 0.680851 (-4250 1050);
PAINT MONO (-4250 1050);
DISPLAY INVISIBLE (-4250 1050);
FORCEPROP 0 LAST CDS_SEC 1
J 0
(-4250 1050);
DISPLAY 1.021277 (-4250 1050);
DISPLAY INVISIBLE (-4250 1050);
FORCEPROP 1 LASTPIN (-4300 975) $PN 1
J 0
(-4295 937);
DISPLAY 0.489362 (-4295 937);
PAINT MONO (-4295 937);
FORCEPROP 1 LASTPIN (-4300 775) $PN 2
J 0
(-4295 785);
DISPLAY 0.489362 (-4295 785);
PAINT MONO (-4295 785);
FORCEPROP 1 LAST WATTAGE 1/8W
J 0
(-4260 850);
DISPLAY 0.489362 (-4260 850);
PAINT SKYBLUE (-4260 850);
FORCEPROP 1 LAST MATERIAL EMPTY
J 0
(-4260 800);
DISPLAY 0.489362 (-4260 800);
PAINT RED (-4260 800);
FORCEPROP 1 LAST TOLERANCE 1%
J 0
(-4255 900);
DISPLAY 0.489362 (-4255 900);
PAINT SKYBLUE (-4255 900);
FORCEPROP 1 LAST VALUE 1.5
J 0
(-4255 950);
DISPLAY 0.489362 (-4255 950);
PAINT SKYBLUE (-4255 950);
FORCEPROP 1 LAST PACK_TYPE 0402LF
J 0
(-4260 700);
DISPLAY 0.489362 (-4260 700);
PAINT SKYBLUE (-4260 700);
FORCEPROP 2 LAST CDS_LIB pure_quanta
J 0
(-4300 875);
DISPLAY INVISIBLE (-4300 875);
FORCEPROP 1 LAST PATH I18
J 0
(-4250 1050);
DISPLAY 0.978723 (-4250 1050);
PAINT WHITE (-4250 1050);
DISPLAY INVISIBLE (-4250 1050);
FORCEPROP 1 LAST PART_NUMBER CS-1504FB00
J 0
(-4260 750);
DISPLAY 0.489362 (-4260 750);
PAINT SKYBLUE (-4260 750);
DISPLAY INVISIBLE (-4260 750);
FORCEADD Q_CAP..1
(-4300 1325);
FORCEPROP 1 LAST LOCATION PC181
J 0
(-4250 1425);
DISPLAY 0.489362 (-4250 1425);
PAINT SKYBLUE (-4250 1425);
FORCEPROP 0 LAST $SEC 1
J 0
(-4250 1475);
DISPLAY 0.680851 (-4250 1475);
PAINT MONO (-4250 1475);
DISPLAY INVISIBLE (-4250 1475);
FORCEPROP 0 LAST CDS_SEC 1
J 0
(-4250 1475);
DISPLAY 1.021277 (-4250 1475);
DISPLAY INVISIBLE (-4250 1475);
FORCEPROP 1 LASTPIN (-4300 1425) $PN 1
J 0
(-4290 1405);
DISPLAY 0.489362 (-4290 1405);
PAINT MONO (-4290 1405);
FORCEPROP 1 LASTPIN (-4300 1225) $PN 2
J 0
(-4290 1205);
DISPLAY 0.489362 (-4290 1205);
PAINT MONO (-4290 1205);
FORCEPROP 1 LAST MATERIAL EMPTY
J 0
(-4250 1225);
DISPLAY 0.489362 (-4250 1225);
PAINT RED (-4250 1225);
FORCEPROP 1 LAST PACK_TYPE C0402
J 0
(-4250 1125);
DISPLAY 0.489362 (-4250 1125);
PAINT SKYBLUE (-4250 1125);
FORCEPROP 1 LAST VALUE 560PF
J 0
(-4250 1375);
DISPLAY 0.489362 (-4250 1375);
PAINT SKYBLUE (-4250 1375);
FORCEPROP 1 LAST VOLTAGE 50V
J 0
(-4250 1325);
DISPLAY 0.489362 (-4250 1325);
PAINT SKYBLUE (-4250 1325);
FORCEPROP 1 LAST TOLERANCE 10%
J 0
(-4250 1275);
DISPLAY 0.489362 (-4250 1275);
PAINT SKYBLUE (-4250 1275);
FORCEPROP 2 LAST CDS_LIB pure_quanta
J 0
(-4300 1325);
DISPLAY INVISIBLE (-4300 1325);
FORCEPROP 1 LAST PATH I19
J 0
(-4250 1475);
DISPLAY 0.978723 (-4250 1475);
PAINT WHITE (-4250 1475);
DISPLAY INVISIBLE (-4250 1475);
FORCEPROP 1 LAST PART_NUMBER CH1566K1B09
J 0
(-4250 1175);
DISPLAY 0.489362 (-4250 1175);
PAINT SKYBLUE (-4250 1175);
DISPLAY INVISIBLE (-4250 1175);
FORCEADD Q_CAP..1
(-7600 1225);
FORCEPROP 1 LAST LOCATION PC545_4
J 0
(-7550 1325);
DISPLAY 0.489362 (-7550 1325);
PAINT SKYBLUE (-7550 1325);
FORCEPROP 0 LAST $SEC 1
J 0
(-7550 1350);
DISPLAY 0.680851 (-7550 1350);
PAINT MONO (-7550 1350);
DISPLAY INVISIBLE (-7550 1350);
FORCEPROP 0 LAST CDS_SEC 1
J 0
(-7550 1350);
DISPLAY 1.021277 (-7550 1350);
DISPLAY INVISIBLE (-7550 1350);
FORCEPROP 1 LASTPIN (-7600 1325) $PN 1
J 0
(-7590 1305);
DISPLAY 0.489362 (-7590 1305);
PAINT MONO (-7590 1305);
FORCEPROP 1 LASTPIN (-7600 1125) $PN 2
J 0
(-7590 1105);
DISPLAY 0.489362 (-7590 1105);
PAINT MONO (-7590 1105);
FORCEPROP 1 LAST MATERIAL X7R
J 0
(-7550 1125);
DISPLAY 0.489362 (-7550 1125);
PAINT SKYBLUE (-7550 1125);
FORCEPROP 1 LAST TOLERANCE 10%
J 0
(-7550 1175);
DISPLAY 0.489362 (-7550 1175);
PAINT SKYBLUE (-7550 1175);
FORCEPROP 1 LAST VALUE 0.1UF
J 0
(-7550 1275);
DISPLAY 0.489362 (-7550 1275);
PAINT SKYBLUE (-7550 1275);
FORCEPROP 1 LAST VOLTAGE 25V
J 0
(-7550 1225);
DISPLAY 0.489362 (-7550 1225);
PAINT SKYBLUE (-7550 1225);
FORCEPROP 1 LAST PACK_TYPE 0402
J 0
(-7550 1025);
DISPLAY 0.489362 (-7550 1025);
PAINT SKYBLUE (-7550 1025);
FORCEPROP 2 LAST CDS_LIB pure_quanta
J 0
(-7600 1225);
DISPLAY INVISIBLE (-7600 1225);
FORCEPROP 1 LAST PATH I2
J 0
(-7550 1375);
DISPLAY 0.978723 (-7550 1375);
PAINT WHITE (-7550 1375);
DISPLAY INVISIBLE (-7550 1375);
FORCEPROP 1 LAST PART_NUMBER CH4104K1B00
J 0
(-7550 1075);
DISPLAY 0.489362 (-7550 1075);
PAINT SKYBLUE (-7550 1075);
DISPLAY INVISIBLE (-7550 1075);
FORCEADD Q_RES..1
(-4375 1850);
FORCEPROP 1 LAST LOCATION PR349
J 0
(-4400 1900);
DISPLAY 0.489362 (-4400 1900);
PAINT SKYBLUE (-4400 1900);
FORCEPROP 0 LAST $SEC 1
J 0
(-4350 1925);
DISPLAY 0.680851 (-4350 1925);
PAINT MONO (-4350 1925);
DISPLAY INVISIBLE (-4350 1925);
FORCEPROP 0 LAST CDS_SEC 1
J 0
(-4350 1925);
DISPLAY 1.021277 (-4350 1925);
DISPLAY INVISIBLE (-4350 1925);
FORCEPROP 1 LASTPIN (-4475 1850) $PN 1
J 0
(-4463 1862);
DISPLAY 0.489362 (-4463 1862);
PAINT MONO (-4463 1862);
FORCEPROP 1 LASTPIN (-4275 1850) $PN 2
J 0
(-4313 1862);
DISPLAY 0.489362 (-4313 1862);
PAINT MONO (-4313 1862);
FORCEPROP 1 LAST VALUE 5.6
J 2
(-4475 1875);
DISPLAY 0.489362 (-4475 1875);
PAINT SKYBLUE (-4475 1875);
FORCEPROP 1 LAST PACK_TYPE 0402LF
J 0
(-4275 1750);
DISPLAY 0.489362 (-4275 1750);
PAINT SKYBLUE (-4275 1750);
FORCEPROP 1 LAST TOLERANCE 1%
J 0
(-4275 1875);
DISPLAY 0.489362 (-4275 1875);
PAINT SKYBLUE (-4275 1875);
FORCEPROP 1 LAST MATERIAL CHIP
J 0
(-4625 1750);
DISPLAY 0.489362 (-4625 1750);
PAINT SKYBLUE (-4625 1750);
FORCEPROP 1 LAST WATTAGE 1/16W
J 0
(-4275 1800);
DISPLAY 0.489362 (-4275 1800);
PAINT SKYBLUE (-4275 1800);
FORCEPROP 2 LAST CDS_LIB pure_quanta
J 0
(-4375 1850);
DISPLAY INVISIBLE (-4375 1850);
FORCEPROP 1 LAST PATH I20
J 0
(-4425 2000);
DISPLAY 0.978723 (-4425 2000);
PAINT WHITE (-4425 2000);
DISPLAY INVISIBLE (-4425 2000);
FORCEPROP 1 LAST PART_NUMBER CS-5602FB01
J 0
(-4625 1800);
DISPLAY 0.489362 (-4625 1800);
PAINT SKYBLUE (-4625 1800);
DISPLAY INVISIBLE (-4625 1800);
FORCEADD Q_CAP..1
(-5100 2400);
FORCEPROP 1 LAST LOCATION PC551_4
J 0
(-5050 2500);
DISPLAY 0.489362 (-5050 2500);
PAINT SKYBLUE (-5050 2500);
FORCEPROP 0 LAST $SEC 1
J 0
(-5050 2550);
DISPLAY 0.680851 (-5050 2550);
PAINT MONO (-5050 2550);
DISPLAY INVISIBLE (-5050 2550);
FORCEPROP 0 LAST CDS_SEC 1
J 0
(-5050 2550);
DISPLAY 1.021277 (-5050 2550);
DISPLAY INVISIBLE (-5050 2550);
FORCEPROP 1 LASTPIN (-5100 2500) $PN 1
J 0
(-5090 2480);
DISPLAY 0.489362 (-5090 2480);
PAINT MONO (-5090 2480);
FORCEPROP 1 LASTPIN (-5100 2300) $PN 2
J 0
(-5090 2280);
DISPLAY 0.489362 (-5090 2280);
PAINT MONO (-5090 2280);
FORCEPROP 1 LAST MATERIAL X7R
J 0
(-5050 2300);
DISPLAY 0.489362 (-5050 2300);
PAINT SKYBLUE (-5050 2300);
FORCEPROP 1 LAST TOLERANCE 10%
J 0
(-5050 2350);
DISPLAY 0.489362 (-5050 2350);
PAINT SKYBLUE (-5050 2350);
FORCEPROP 1 LAST VALUE 0.1UF
J 0
(-5050 2450);
DISPLAY 0.489362 (-5050 2450);
PAINT SKYBLUE (-5050 2450);
FORCEPROP 1 LAST VOLTAGE 25V
J 0
(-5050 2400);
DISPLAY 0.489362 (-5050 2400);
PAINT SKYBLUE (-5050 2400);
FORCEPROP 1 LAST PACK_TYPE 0402
J 0
(-5050 2200);
DISPLAY 0.489362 (-5050 2200);
PAINT SKYBLUE (-5050 2200);
FORCEPROP 2 LAST CDS_LIB pure_quanta
J 0
(-5100 2400);
DISPLAY INVISIBLE (-5100 2400);
FORCEPROP 1 LAST PATH I21
J 0
(-5050 2550);
DISPLAY 0.978723 (-5050 2550);
PAINT WHITE (-5050 2550);
DISPLAY INVISIBLE (-5050 2550);
FORCEPROP 1 LAST PART_NUMBER CH4104K1B00
J 0
(-5050 2250);
DISPLAY 0.489362 (-5050 2250);
PAINT SKYBLUE (-5050 2250);
DISPLAY INVISIBLE (-5050 2250);
FORCEADD Q_CAP..1
(-4725 2400);
FORCEPROP 1 LAST LOCATION PC553_4
J 0
(-4675 2500);
DISPLAY 0.489362 (-4675 2500);
PAINT SKYBLUE (-4675 2500);
FORCEPROP 0 LAST $SEC 1
J 0
(-4675 2525);
DISPLAY 0.680851 (-4675 2525);
PAINT MONO (-4675 2525);
DISPLAY INVISIBLE (-4675 2525);
FORCEPROP 0 LAST CDS_SEC 1
J 0
(-4675 2525);
DISPLAY 1.021277 (-4675 2525);
DISPLAY INVISIBLE (-4675 2525);
FORCEPROP 1 LASTPIN (-4725 2500) $PN 1
J 0
(-4715 2480);
DISPLAY 0.489362 (-4715 2480);
PAINT MONO (-4715 2480);
FORCEPROP 1 LASTPIN (-4725 2300) $PN 2
J 0
(-4715 2280);
DISPLAY 0.489362 (-4715 2280);
PAINT MONO (-4715 2280);
FORCEPROP 1 LAST MATERIAL X6S
J 0
(-4675 2300);
DISPLAY 0.489362 (-4675 2300);
PAINT SKYBLUE (-4675 2300);
FORCEPROP 1 LAST TOLERANCE 10%
J 0
(-4675 2350);
DISPLAY 0.489362 (-4675 2350);
PAINT SKYBLUE (-4675 2350);
FORCEPROP 1 LAST VOLTAGE 25V
J 0
(-4675 2400);
DISPLAY 0.489362 (-4675 2400);
PAINT SKYBLUE (-4675 2400);
FORCEPROP 1 LAST VALUE 1UF
J 0
(-4675 2450);
DISPLAY 0.489362 (-4675 2450);
PAINT SKYBLUE (-4675 2450);
FORCEPROP 1 LAST PACK_TYPE C0402
J 0
(-4675 2200);
DISPLAY 0.489362 (-4675 2200);
PAINT SKYBLUE (-4675 2200);
FORCEPROP 2 LAST CDS_LIB pure_quanta
J 0
(-4725 2400);
DISPLAY INVISIBLE (-4725 2400);
FORCEPROP 1 LAST PATH I22
J 0
(-4675 2550);
DISPLAY 0.978723 (-4675 2550);
PAINT WHITE (-4675 2550);
DISPLAY INVISIBLE (-4675 2550);
FORCEPROP 1 LAST PART_NUMBER CH5104KEB02
J 0
(-4675 2250);
DISPLAY 0.489362 (-4675 2250);
PAINT SKYBLUE (-4675 2250);
DISPLAY INVISIBLE (-4675 2250);
FORCEADD Q_CAP..1
(-4400 2400);
FORCEPROP 1 LAST LOCATION PC555_4
J 0
(-4350 2500);
DISPLAY 0.489362 (-4350 2500);
PAINT SKYBLUE (-4350 2500);
FORCEPROP 0 LAST $SEC 1
J 0
(-4350 2525);
DISPLAY 0.680851 (-4350 2525);
PAINT MONO (-4350 2525);
DISPLAY INVISIBLE (-4350 2525);
FORCEPROP 0 LAST CDS_SEC 1
J 0
(-4350 2525);
DISPLAY 1.021277 (-4350 2525);
DISPLAY INVISIBLE (-4350 2525);
FORCEPROP 1 LASTPIN (-4400 2500) $PN 1
J 0
(-4390 2480);
DISPLAY 0.489362 (-4390 2480);
PAINT MONO (-4390 2480);
FORCEPROP 1 LASTPIN (-4400 2300) $PN 2
J 0
(-4390 2280);
DISPLAY 0.489362 (-4390 2280);
PAINT MONO (-4390 2280);
FORCEPROP 1 LAST TOLERANCE 20%
J 0
(-4350 2350);
DISPLAY 0.489362 (-4350 2350);
PAINT SKYBLUE (-4350 2350);
FORCEPROP 1 LAST MATERIAL X6S
J 0
(-4350 2300);
DISPLAY 0.489362 (-4350 2300);
PAINT SKYBLUE (-4350 2300);
FORCEPROP 1 LAST PACK_TYPE C0805
J 0
(-4350 2200);
DISPLAY 0.489362 (-4350 2200);
PAINT SKYBLUE (-4350 2200);
FORCEPROP 1 LAST VOLTAGE 16V
J 0
(-4350 2400);
DISPLAY 0.489362 (-4350 2400);
PAINT SKYBLUE (-4350 2400);
FORCEPROP 1 LAST VALUE 22UF
J 0
(-4350 2450);
DISPLAY 0.489362 (-4350 2450);
PAINT SKYBLUE (-4350 2450);
FORCEPROP 2 LAST CDS_LIB pure_quanta
J 0
(-4400 2400);
DISPLAY INVISIBLE (-4400 2400);
FORCEPROP 1 LAST PATH I23
J 0
(-4350 2550);
DISPLAY 0.978723 (-4350 2550);
PAINT WHITE (-4350 2550);
DISPLAY INVISIBLE (-4350 2550);
FORCEPROP 1 LAST PART_NUMBER CH6223MEA01
J 0
(-4350 2250);
DISPLAY 0.489362 (-4350 2250);
PAINT SKYBLUE (-4350 2250);
DISPLAY INVISIBLE (-4350 2250);
FORCEADD Q_CAP..1
(-4075 2400);
FORCEPROP 1 LAST LOCATION PC557_4
J 0
(-4025 2500);
DISPLAY 0.489362 (-4025 2500);
PAINT SKYBLUE (-4025 2500);
FORCEPROP 0 LAST $SEC 1
J 0
(-4025 2525);
DISPLAY 0.680851 (-4025 2525);
PAINT MONO (-4025 2525);
DISPLAY INVISIBLE (-4025 2525);
FORCEPROP 0 LAST CDS_SEC 1
J 0
(-4025 2525);
DISPLAY 1.021277 (-4025 2525);
DISPLAY INVISIBLE (-4025 2525);
FORCEPROP 1 LASTPIN (-4075 2500) $PN 1
J 0
(-4065 2480);
DISPLAY 0.489362 (-4065 2480);
PAINT MONO (-4065 2480);
FORCEPROP 1 LASTPIN (-4075 2300) $PN 2
J 0
(-4065 2280);
DISPLAY 0.489362 (-4065 2280);
PAINT MONO (-4065 2280);
FORCEPROP 1 LAST MATERIAL X6S
J 0
(-4025 2300);
DISPLAY 0.489362 (-4025 2300);
PAINT SKYBLUE (-4025 2300);
FORCEPROP 1 LAST PACK_TYPE C0805
J 0
(-4025 2200);
DISPLAY 0.489362 (-4025 2200);
PAINT SKYBLUE (-4025 2200);
FORCEPROP 1 LAST VOLTAGE 16V
J 0
(-4025 2400);
DISPLAY 0.489362 (-4025 2400);
PAINT SKYBLUE (-4025 2400);
FORCEPROP 1 LAST TOLERANCE 20%
J 0
(-4025 2350);
DISPLAY 0.489362 (-4025 2350);
PAINT SKYBLUE (-4025 2350);
FORCEPROP 1 LAST VALUE 22UF
J 0
(-4025 2450);
DISPLAY 0.489362 (-4025 2450);
PAINT SKYBLUE (-4025 2450);
FORCEPROP 2 LAST CDS_LIB pure_quanta
J 0
(-4075 2400);
DISPLAY INVISIBLE (-4075 2400);
FORCEPROP 1 LAST PATH I24
J 0
(-4025 2550);
DISPLAY 0.978723 (-4025 2550);
PAINT WHITE (-4025 2550);
DISPLAY INVISIBLE (-4025 2550);
FORCEPROP 1 LAST PART_NUMBER CH6223MEA01
J 0
(-4025 2250);
DISPLAY 0.489362 (-4025 2250);
PAINT SKYBLUE (-4025 2250);
DISPLAY INVISIBLE (-4025 2250);
FORCEADD UNIVERSAL_GND..1
(-4375 3925);
FORCEPROP 3 LASTPIN (-4375 3975) SIG_NAME GND\g
J 0
(-4365 3985);
DISPLAY 0.659574 (-4365 3985);
PAINT MONO (-4365 3985);
DISPLAY INVISIBLE (-4365 3985);
FORCEPROP 2 LAST CDS_LIB pure_quanta_power
J 0
(-4375 3925);
DISPLAY INVISIBLE (-4375 3925);
FORCEPROP 1 LAST HDL_POWER GND
J 1
(-4350 3850);
DISPLAY 0.872340 (-4350 3850);
PAINT GREEN (-4350 3850);
DISPLAY INVISIBLE (-4350 3850);
FORCEPROP 1 LAST PATH I25
J 0
(-4300 3925);
DISPLAY 0.872340 (-4300 3925);
PAINT AQUA (-4300 3925);
DISPLAY INVISIBLE (-4300 3925);
FORCEADD Q_RES..1
(-4050 3850);
FORCEPROP 1 LAST LOCATION PR350
J 0
(-4075 3900);
DISPLAY 0.489362 (-4075 3900);
PAINT SKYBLUE (-4075 3900);
FORCEPROP 0 LAST $SEC 1
J 0
(-4050 3925);
DISPLAY 0.680851 (-4050 3925);
PAINT MONO (-4050 3925);
DISPLAY INVISIBLE (-4050 3925);
FORCEPROP 0 LAST CDS_SEC 1
J 0
(-4050 3925);
DISPLAY 1.021277 (-4050 3925);
DISPLAY INVISIBLE (-4050 3925);
FORCEPROP 1 LASTPIN (-4150 3850) $PN 1
J 0
(-4138 3862);
DISPLAY 0.489362 (-4138 3862);
PAINT MONO (-4138 3862);
FORCEPROP 1 LASTPIN (-3950 3850) $PN 2
J 0
(-3988 3862);
DISPLAY 0.489362 (-3988 3862);
PAINT MONO (-3988 3862);
FORCEPROP 1 LAST PACK_TYPE 0402LF
J 0
(-4275 3750);
DISPLAY 0.489362 (-4275 3750);
PAINT SKYBLUE (-4275 3750);
FORCEPROP 1 LAST VALUE 0
J 2
(-4175 3875);
DISPLAY 0.489362 (-4175 3875);
PAINT SKYBLUE (-4175 3875);
FORCEPROP 1 LAST TOLERANCE 5%
J 0
(-3925 3875);
DISPLAY 0.489362 (-3925 3875);
PAINT SKYBLUE (-3925 3875);
FORCEPROP 1 LAST MATERIAL CHIP
J 0
(-3925 3750);
DISPLAY 0.489362 (-3925 3750);
PAINT SKYBLUE (-3925 3750);
FORCEPROP 1 LAST WATTAGE 1/16W
J 0
(-3950 3800);
DISPLAY 0.489362 (-3950 3800);
PAINT SKYBLUE (-3950 3800);
FORCEPROP 2 LAST CDS_LIB pure_quanta
J 0
(-4050 3850);
DISPLAY INVISIBLE (-4050 3850);
FORCEPROP 1 LAST PATH I26
J 0
(-4100 4000);
DISPLAY 0.978723 (-4100 4000);
PAINT WHITE (-4100 4000);
DISPLAY INVISIBLE (-4100 4000);
FORCEPROP 1 LAST PART_NUMBER CS00002JB13
J 0
(-4300 3800);
DISPLAY 0.489362 (-4300 3800);
PAINT SKYBLUE (-4300 3800);
DISPLAY INVISIBLE (-4300 3800);
FORCEADD Q_CAP..1
(-7675 4525);
FORCEPROP 1 LAST LOCATION PC544_3
J 0
(-7625 4625);
DISPLAY 0.489362 (-7625 4625);
PAINT SKYBLUE (-7625 4625);
FORCEPROP 0 LAST $SEC 1
J 0
(-7625 4650);
DISPLAY 0.680851 (-7625 4650);
PAINT MONO (-7625 4650);
DISPLAY INVISIBLE (-7625 4650);
FORCEPROP 0 LAST CDS_SEC 1
J 0
(-7625 4650);
DISPLAY 1.021277 (-7625 4650);
DISPLAY INVISIBLE (-7625 4650);
FORCEPROP 1 LASTPIN (-7675 4625) $PN 1
J 0
(-7665 4605);
DISPLAY 0.489362 (-7665 4605);
PAINT MONO (-7665 4605);
FORCEPROP 1 LASTPIN (-7675 4425) $PN 2
J 0
(-7665 4405);
DISPLAY 0.489362 (-7665 4405);
PAINT MONO (-7665 4405);
FORCEPROP 1 LAST MATERIAL X7R
J 0
(-7625 4425);
DISPLAY 0.489362 (-7625 4425);
PAINT SKYBLUE (-7625 4425);
FORCEPROP 1 LAST TOLERANCE 10%
J 0
(-7625 4475);
DISPLAY 0.489362 (-7625 4475);
PAINT SKYBLUE (-7625 4475);
FORCEPROP 1 LAST VALUE 0.1UF
J 0
(-7625 4575);
DISPLAY 0.489362 (-7625 4575);
PAINT SKYBLUE (-7625 4575);
FORCEPROP 1 LAST VOLTAGE 25V
J 0
(-7625 4525);
DISPLAY 0.489362 (-7625 4525);
PAINT SKYBLUE (-7625 4525);
FORCEPROP 1 LAST PACK_TYPE 0402
J 0
(-7625 4325);
DISPLAY 0.489362 (-7625 4325);
PAINT SKYBLUE (-7625 4325);
FORCEPROP 2 LAST CDS_LIB pure_quanta
J 0
(-7675 4525);
DISPLAY INVISIBLE (-7675 4525);
FORCEPROP 1 LAST PATH I27
J 0
(-7625 4675);
DISPLAY 0.978723 (-7625 4675);
PAINT WHITE (-7625 4675);
DISPLAY INVISIBLE (-7625 4675);
FORCEPROP 1 LAST PART_NUMBER CH4104K1B00
J 0
(-7625 4375);
DISPLAY 0.489362 (-7625 4375);
PAINT SKYBLUE (-7625 4375);
DISPLAY INVISIBLE (-7625 4375);
FORCEADD UNIVERSAL_GND..1
(-7675 4250);
FORCEPROP 3 LASTPIN (-7675 4300) SIG_NAME GND\g
J 0
(-7665 4310);
DISPLAY 0.659574 (-7665 4310);
PAINT MONO (-7665 4310);
DISPLAY INVISIBLE (-7665 4310);
FORCEPROP 2 LAST CDS_LIB pure_quanta_power
J 0
(-7675 4250);
DISPLAY INVISIBLE (-7675 4250);
FORCEPROP 1 LAST HDL_POWER GND
J 1
(-7650 4175);
DISPLAY 0.872340 (-7650 4175);
PAINT GREEN (-7650 4175);
DISPLAY INVISIBLE (-7650 4175);
FORCEPROP 1 LAST PATH I28
J 0
(-7600 4250);
DISPLAY 0.872340 (-7600 4250);
PAINT AQUA (-7600 4250);
DISPLAY INVISIBLE (-7600 4250);
FORCEADD OFFPAGE..1
(-7900 4700);
FORCEPROP 2 LAST $XR5 199 
J 0
(-8752 4700);
DISPLAY 0.638298 (-8752 4700);
PAINT MONO (-8752 4700);
FORCEPROP 2 LAST $XR4 198 
J 0
(-8632 4700);
DISPLAY 0.638298 (-8632 4700);
PAINT MONO (-8632 4700);
FORCEPROP 2 LAST $XR3 196 
J 0
(-8512 4700);
DISPLAY 0.638298 (-8512 4700);
PAINT MONO (-8512 4700);
FORCEPROP 2 LAST $XR2 195 
J 0
(-8392 4700);
DISPLAY 0.638298 (-8392 4700);
PAINT MONO (-8392 4700);
FORCEPROP 2 LAST $XR1 194 
J 0
(-8272 4700);
DISPLAY 0.638298 (-8272 4700);
PAINT MONO (-8272 4700);
FORCEPROP 2 LAST $XR0 193 
J 0
(-8152 4700);
DISPLAY 0.638298 (-8152 4700);
PAINT MONO (-8152 4700);
FORCEPROP 2 LAST CDS_LIB standard
J 0
(-7900 4700);
DISPLAY INVISIBLE (-7900 4700);
FORCEPROP 1 LAST OFFPAGE TRUE
J 0
(-7575 4575);
DISPLAY 0.872340 (-7575 4575);
PAINT GREEN (-7575 4575);
DISPLAY INVISIBLE (-7575 4575);
FORCEPROP 1 LAST COMMENT_BODY TRUE
J 0
(-7775 4600);
DISPLAY 0.872340 (-7775 4600);
PAINT GREEN (-7775 4600);
DISPLAY INVISIBLE (-7775 4600);
FORCEPROP 2 LAST PATH I29
J 0
(-8150 4750);
DISPLAY 0.680851 (-8150 4750);
DISPLAY INVISIBLE (-8150 4750);
FORCEADD UNIVERSAL_GND..1
(-7600 950);
FORCEPROP 3 LASTPIN (-7600 1000) SIG_NAME GND\g
J 0
(-7590 1010);
DISPLAY 0.659574 (-7590 1010);
PAINT MONO (-7590 1010);
DISPLAY INVISIBLE (-7590 1010);
FORCEPROP 2 LAST CDS_LIB pure_quanta_power
J 0
(-7600 950);
DISPLAY INVISIBLE (-7600 950);
FORCEPROP 1 LAST HDL_POWER GND
J 1
(-7575 875);
DISPLAY 0.872340 (-7575 875);
PAINT GREEN (-7575 875);
DISPLAY INVISIBLE (-7575 875);
FORCEPROP 1 LAST PATH I3
J 0
(-7525 950);
DISPLAY 0.872340 (-7525 950);
PAINT AQUA (-7525 950);
DISPLAY INVISIBLE (-7525 950);
FORCEADD UNIVERSAL_GND..1
(-7350 4325);
FORCEPROP 3 LASTPIN (-7350 4375) SIG_NAME GND\g
J 0
(-7340 4385);
DISPLAY 0.659574 (-7340 4385);
PAINT MONO (-7340 4385);
DISPLAY INVISIBLE (-7340 4385);
FORCEPROP 2 LAST CDS_LIB pure_quanta_power
J 0
(-7350 4325);
DISPLAY INVISIBLE (-7350 4325);
FORCEPROP 1 LAST HDL_POWER GND
J 1
(-7325 4250);
DISPLAY 0.872340 (-7325 4250);
PAINT GREEN (-7325 4250);
DISPLAY INVISIBLE (-7325 4250);
FORCEPROP 1 LAST PATH I30
J 0
(-7275 4325);
DISPLAY 0.872340 (-7275 4325);
PAINT AQUA (-7275 4325);
DISPLAY INVISIBLE (-7275 4325);
FORCEADD OFFPAGE..1
(-6950 4200);
FORCEPROP 2 LAST $XR0 193 
J 0
(-7202 4200);
DISPLAY 0.638298 (-7202 4200);
PAINT MONO (-7202 4200);
FORCEPROP 2 LAST CDS_LIB standard
J 2
(-6950 4200);
DISPLAY INVISIBLE (-6950 4200);
FORCEPROP 1 LAST OFFPAGE TRUE
J 0
(-6625 4075);
DISPLAY 0.872340 (-6625 4075);
PAINT GREEN (-6625 4075);
DISPLAY INVISIBLE (-6625 4075);
FORCEPROP 1 LAST COMMENT_BODY TRUE
J 0
(-6825 4100);
DISPLAY 0.872340 (-6825 4100);
PAINT GREEN (-6825 4100);
DISPLAY INVISIBLE (-6825 4100);
FORCEPROP 2 LAST PATH I31
J 0
(-7200 4250);
DISPLAY 0.680851 (-7200 4250);
DISPLAY INVISIBLE (-7200 4250);
FORCEADD OFFPAGE..2
R 2
(-6975 4300);
FORCEPROP 2 LAST $XR3 193 
J 0
(-7470 4264);
DISPLAY 0.638298 (-7470 4264);
PAINT MONO (-7470 4264);
FORCEPROP 2 LAST $XR2 196 
J 0
(-7350 4264);
DISPLAY 0.638298 (-7350 4264);
PAINT MONO (-7350 4264);
FORCEPROP 2 LAST $XR1 195 
J 0
(-7230 4264);
DISPLAY 0.638298 (-7230 4264);
PAINT MONO (-7230 4264);
FORCEPROP 2 LAST $XR0 194 
J 0
(-7230 4300);
DISPLAY 0.638298 (-7230 4300);
PAINT MONO (-7230 4300);
FORCEPROP 2 LAST CDS_LIB standard
J 0
(-6975 4300);
DISPLAY INVISIBLE (-6975 4300);
FORCEPROP 1 LAST OFFPAGE TRUE
J 2
(-7300 4175);
DISPLAY 0.872340 (-7300 4175);
PAINT GREEN (-7300 4175);
DISPLAY INVISIBLE (-7300 4175);
FORCEPROP 1 LAST COMMENT_BODY TRUE
J 2
(-6930 4205);
DISPLAY 0.872340 (-6930 4205);
PAINT GREEN (-6930 4205);
DISPLAY INVISIBLE (-6930 4205);
FORCEPROP 2 LAST PATH I32
J 0
(-7250 4350);
DISPLAY 0.680851 (-7250 4350);
DISPLAY INVISIBLE (-7250 4350);
FORCEADD Q_RES..1
(-7025 4500);
FORCEPROP 1 LAST LOCATION PR346
J 0
(-7075 4550);
DISPLAY 0.489362 (-7075 4550);
PAINT SKYBLUE (-7075 4550);
FORCEPROP 0 LAST $SEC 1
J 0
(-7025 4575);
DISPLAY 0.680851 (-7025 4575);
PAINT MONO (-7025 4575);
DISPLAY INVISIBLE (-7025 4575);
FORCEPROP 0 LAST CDS_SEC 1
J 0
(-7025 4575);
DISPLAY 1.021277 (-7025 4575);
DISPLAY INVISIBLE (-7025 4575);
FORCEPROP 1 LASTPIN (-7125 4500) $PN 1
J 0
(-7113 4512);
DISPLAY 0.489362 (-7113 4512);
PAINT MONO (-7113 4512);
FORCEPROP 1 LASTPIN (-6925 4500) $PN 2
J 0
(-6963 4512);
DISPLAY 0.489362 (-6963 4512);
PAINT MONO (-6963 4512);
FORCEPROP 1 LAST PACK_TYPE 0402LF
J 0
(-6925 4450);
DISPLAY 0.489362 (-6925 4450);
PAINT SKYBLUE (-6925 4450);
FORCEPROP 1 LAST VALUE 8.87K
J 2
(-7150 4525);
DISPLAY 0.489362 (-7150 4525);
PAINT SKYBLUE (-7150 4525);
FORCEPROP 1 LAST TOLERANCE 1%
J 0
(-6900 4525);
DISPLAY 0.489362 (-6900 4525);
PAINT SKYBLUE (-6900 4525);
FORCEPROP 1 LAST MATERIAL EMPTY
J 0
(-7325 4400);
DISPLAY 0.489362 (-7325 4400);
PAINT RED (-7325 4400);
FORCEPROP 1 LAST WATTAGE 1/16W
J 0
(-6925 4400);
DISPLAY 0.489362 (-6925 4400);
PAINT SKYBLUE (-6925 4400);
FORCEPROP 2 LAST CDS_LIB pure_quanta
J 0
(-7025 4500);
DISPLAY INVISIBLE (-7025 4500);
FORCEPROP 1 LAST PATH I33
J 0
(-7075 4650);
DISPLAY 0.978723 (-7075 4650);
PAINT WHITE (-7075 4650);
DISPLAY INVISIBLE (-7075 4650);
FORCEPROP 1 LAST PART_NUMBER CS28872FB01
J 0
(-7325 4450);
DISPLAY 0.489362 (-7325 4450);
PAINT SKYBLUE (-7325 4450);
DISPLAY INVISIBLE (-7325 4450);
FORCEADD UNIVERSAL_GND..1
(-7350 4950);
FORCEPROP 3 LASTPIN (-7350 5000) SIG_NAME GND\g
J 0
(-7340 5010);
DISPLAY 0.659574 (-7340 5010);
PAINT MONO (-7340 5010);
DISPLAY INVISIBLE (-7340 5010);
FORCEPROP 2 LAST CDS_LIB pure_quanta_power
J 0
(-7350 4950);
DISPLAY INVISIBLE (-7350 4950);
FORCEPROP 1 LAST HDL_POWER GND
J 1
(-7325 4875);
DISPLAY 0.872340 (-7325 4875);
PAINT GREEN (-7325 4875);
DISPLAY INVISIBLE (-7325 4875);
FORCEPROP 1 LAST PATH I34
J 0
(-7275 4950);
DISPLAY 0.872340 (-7275 4950);
PAINT AQUA (-7275 4950);
DISPLAY INVISIBLE (-7275 4950);
FORCEADD OFFPAGE..2
R 2
(-7000 4800);
FORCEPROP 2 LAST $XR0 193 
J 0
(-7255 4800);
DISPLAY 0.638298 (-7255 4800);
PAINT MONO (-7255 4800);
FORCEPROP 2 LAST CDS_LIB standard
J 2
(-7000 4800);
DISPLAY INVISIBLE (-7000 4800);
FORCEPROP 1 LAST OFFPAGE TRUE
J 2
(-7325 4675);
DISPLAY 0.872340 (-7325 4675);
PAINT GREEN (-7325 4675);
DISPLAY INVISIBLE (-7325 4675);
FORCEPROP 1 LAST COMMENT_BODY TRUE
J 2
(-6955 4705);
DISPLAY 0.872340 (-6955 4705);
PAINT GREEN (-6955 4705);
DISPLAY INVISIBLE (-6955 4705);
FORCEPROP 2 LAST PATH I35
J 0
(-7250 4850);
DISPLAY 0.680851 (-7250 4850);
DISPLAY INVISIBLE (-7250 4850);
FORCEADD Q_CAP..1
(-7350 5150);
FORCEPROP 1 LAST LOCATION PC546
J 0
(-7300 5250);
DISPLAY 0.489362 (-7300 5250);
PAINT SKYBLUE (-7300 5250);
FORCEPROP 0 LAST $SEC 1
J 0
(-7300 5300);
DISPLAY 0.680851 (-7300 5300);
PAINT MONO (-7300 5300);
DISPLAY INVISIBLE (-7300 5300);
FORCEPROP 0 LAST CDS_SEC 1
J 0
(-7300 5300);
DISPLAY 1.021277 (-7300 5300);
DISPLAY INVISIBLE (-7300 5300);
FORCEPROP 1 LASTPIN (-7350 5250) $PN 1
J 0
(-7340 5230);
DISPLAY 0.489362 (-7340 5230);
PAINT MONO (-7340 5230);
FORCEPROP 1 LASTPIN (-7350 5050) $PN 2
J 0
(-7340 5030);
DISPLAY 0.489362 (-7340 5030);
PAINT MONO (-7340 5030);
FORCEPROP 1 LAST MATERIAL X6S
J 0
(-7300 5050);
DISPLAY 0.489362 (-7300 5050);
PAINT SKYBLUE (-7300 5050);
FORCEPROP 1 LAST TOLERANCE 10%
J 0
(-7300 5100);
DISPLAY 0.489362 (-7300 5100);
PAINT SKYBLUE (-7300 5100);
FORCEPROP 1 LAST VALUE 2.2UF
J 0
(-7300 5200);
DISPLAY 0.489362 (-7300 5200);
PAINT SKYBLUE (-7300 5200);
FORCEPROP 1 LAST VOLTAGE 10V
J 0
(-7300 5150);
DISPLAY 0.489362 (-7300 5150);
PAINT SKYBLUE (-7300 5150);
FORCEPROP 1 LAST PACK_TYPE C0402
J 0
(-7300 4950);
DISPLAY 0.489362 (-7300 4950);
PAINT SKYBLUE (-7300 4950);
FORCEPROP 2 LAST CDS_LIB pure_quanta
J 0
(-7350 5150);
DISPLAY INVISIBLE (-7350 5150);
FORCEPROP 1 LAST PATH I36
J 0
(-7300 5300);
DISPLAY 0.978723 (-7300 5300);
PAINT WHITE (-7300 5300);
DISPLAY INVISIBLE (-7300 5300);
FORCEPROP 1 LAST PART_NUMBER CH5222KEB01
J 0
(-7300 5000);
DISPLAY 0.489362 (-7300 5000);
PAINT SKYBLUE (-7300 5000);
DISPLAY INVISIBLE (-7300 5000);
FORCEADD Q_RES..2
(-7350 5650);
FORCEPROP 1 LAST LOCATION PR344
J 0
(-7300 5750);
DISPLAY 0.489362 (-7300 5750);
PAINT SKYBLUE (-7300 5750);
FORCEPROP 0 LAST $SEC 1
J 0
(-7300 5825);
DISPLAY 0.680851 (-7300 5825);
PAINT MONO (-7300 5825);
DISPLAY INVISIBLE (-7300 5825);
FORCEPROP 0 LAST CDS_SEC 1
J 0
(-7300 5825);
DISPLAY 1.021277 (-7300 5825);
DISPLAY INVISIBLE (-7300 5825);
FORCEPROP 1 LASTPIN (-7350 5750) $PN 1
J 0
(-7345 5712);
DISPLAY 0.489362 (-7345 5712);
PAINT MONO (-7345 5712);
FORCEPROP 1 LASTPIN (-7350 5550) $PN 2
J 0
(-7345 5560);
DISPLAY 0.489362 (-7345 5560);
PAINT MONO (-7345 5560);
FORCEPROP 1 LAST VALUE 2.2
J 0
(-7300 5700);
DISPLAY 0.489362 (-7300 5700);
PAINT SKYBLUE (-7300 5700);
FORCEPROP 1 LAST TOLERANCE 1%
J 0
(-7300 5650);
DISPLAY 0.489362 (-7300 5650);
PAINT SKYBLUE (-7300 5650);
FORCEPROP 1 LAST MATERIAL CHIP
J 0
(-7300 5550);
DISPLAY 0.489362 (-7300 5550);
PAINT SKYBLUE (-7300 5550);
FORCEPROP 1 LAST WATTAGE 1/16W
J 0
(-7300 5600);
DISPLAY 0.489362 (-7300 5600);
PAINT SKYBLUE (-7300 5600);
FORCEPROP 1 LAST PACK_TYPE 0402LF
J 0
(-7300 5450);
DISPLAY 0.489362 (-7300 5450);
PAINT SKYBLUE (-7300 5450);
FORCEPROP 2 LAST CDS_LIB pure_quanta
J 0
(-7350 5650);
DISPLAY INVISIBLE (-7350 5650);
FORCEPROP 1 LAST PATH I37
J 0
(-7300 5825);
DISPLAY 0.978723 (-7300 5825);
PAINT WHITE (-7300 5825);
DISPLAY INVISIBLE (-7300 5825);
FORCEPROP 1 LAST PART_NUMBER CS-2202FB01
J 0
(-7300 5500);
DISPLAY 0.489362 (-7300 5500);
PAINT SKYBLUE (-7300 5500);
DISPLAY INVISIBLE (-7300 5500);
FORCEADD ISL99390FRZTR5935..1
(-5850 4800);
FORCEPROP 1 LAST LOCATION PU46
J 0
(-6150 5675);
DISPLAY 0.489362 (-6150 5675);
PAINT SKYBLUE (-6150 5675);
FORCEPROP 0 LAST $SEC 1
J 0
(-6150 5825);
DISPLAY 0.680851 (-6150 5825);
PAINT MONO (-6150 5825);
DISPLAY INVISIBLE (-6150 5825);
FORCEPROP 0 LAST CDS_SEC 1
J 0
(-6150 5825);
DISPLAY 1.021277 (-6150 5825);
DISPLAY INVISIBLE (-6150 5825);
FORCEPROP 0 LASTPIN (-5450 4350) $PN 2
J 0
(-5440 4360);
DISPLAY 0.489362 (-5440 4360);
PAINT MONO (-5440 4360);
FORCEPROP 0 LASTPIN (-5450 5150) $PN 33
J 0
(-5440 5160);
DISPLAY 0.489362 (-5440 5160);
PAINT MONO (-5440 5160);
FORCEPROP 0 LASTPIN (-6300 4550) $PN 31
J 2
(-6310 4560);
DISPLAY 0.489362 (-6310 4560);
PAINT MONO (-6310 4560);
FORCEPROP 0 LASTPIN (-6300 4950) $PN 35
J 2
(-6310 4960);
DISPLAY 0.489362 (-6310 4960);
PAINT MONO (-6310 4960);
FORCEPROP 0 LASTPIN (-5450 4500) $PN 6
J 0
(-5440 4510);
DISPLAY 0.489362 (-5440 4510);
PAINT MONO (-5440 4510);
FORCEPROP 0 LASTPIN (-5450 4450) $PN 41
J 0
(-5440 4460);
DISPLAY 0.489362 (-5440 4460);
PAINT MONO (-5440 4460);
FORCEPROP 0 LASTPIN (-6300 4800) $PN 38
J 2
(-6310 4810);
DISPLAY 0.489362 (-6310 4810);
PAINT MONO (-6310 4810);
FORCEPROP 0 LASTPIN (-6300 4500) $PN 37
J 2
(-6310 4510);
DISPLAY 0.489362 (-6310 4510);
PAINT MONO (-6310 4510);
FORCEPROP 0 LASTPIN (-5450 4300) $PN 5
J 0
(-5440 4310);
DISPLAY 0.489362 (-5440 4310);
PAINT MONO (-5440 4310);
FORCEPROP 0 LASTPIN (-5450 4250) $PN 7_9-20_24
J 0
(-5440 4260);
DISPLAY 0.489362 (-5440 4260);
PAINT MONO (-5440 4260);
FORCEPROP 0 LASTPIN (-5450 4200) $PN 40
J 0
(-5440 4210);
DISPLAY 0.489362 (-5440 4210);
PAINT MONO (-5440 4210);
FORCEPROP 0 LASTPIN (-5450 4900) $PN 32
J 0
(-5440 4910);
DISPLAY 0.489362 (-5440 4910);
PAINT MONO (-5440 4910);
FORCEPROP 0 LASTPIN (-6300 5450) $PN 4
J 2
(-6310 5460);
DISPLAY 0.489362 (-6310 5460);
PAINT MONO (-6310 5460);
FORCEPROP 0 LASTPIN (-6300 4200) $PN 34
J 2
(-6310 4210);
DISPLAY 0.489362 (-6310 4210);
PAINT MONO (-6310 4210);
FORCEPROP 0 LASTPIN (-6300 4700) $PN 39
J 2
(-6310 4710);
DISPLAY 0.489362 (-6310 4710);
PAINT MONO (-6310 4710);
FORCEPROP 0 LASTPIN (-5450 4800) $PN 10_19
J 0
(-5440 4810);
DISPLAY 0.489362 (-5440 4810);
PAINT MONO (-5440 4810);
FORCEPROP 0 LASTPIN (-6300 4300) $PN 36
J 2
(-6310 4310);
DISPLAY 0.489362 (-6310 4310);
PAINT MONO (-6310 4310);
FORCEPROP 0 LASTPIN (-6300 5150) $PN 3
J 2
(-6310 5160);
DISPLAY 0.489362 (-6310 5160);
PAINT MONO (-6310 5160);
FORCEPROP 0 LASTPIN (-5450 5450) $PN 25_29
J 0
(-5440 5460);
DISPLAY 0.489362 (-5440 5460);
PAINT MONO (-5440 5460);
FORCEPROP 0 LASTPIN (-5450 5400) $PN 30
J 0
(-5440 5410);
DISPLAY 0.489362 (-5440 5410);
PAINT MONO (-5440 5410);
FORCEPROP 0 LASTPIN (-5450 4550) $PN 1
J 0
(-5440 4560);
DISPLAY 0.489362 (-5440 4560);
PAINT MONO (-5440 4560);
FORCEPROP 1 LAST MATERIAL IC
J 0
(-6150 5525);
DISPLAY 0.489362 (-6150 5525);
PAINT SKYBLUE (-6150 5525);
FORCEPROP 2 LAST PART_TYPE SMLF
J 0
(-6150 5775);
DISPLAY 1.021277 (-6150 5775);
FORCEPROP 2 LAST VALUE ISL99390FRZ-TR5935
J 0
(-6150 5725);
DISPLAY 0.489362 (-6150 5725);
PAINT SKYBLUE (-6150 5725);
FORCEPROP 2 LAST CDS_LIB pure_quanta
J 0
(-5850 4800);
DISPLAY INVISIBLE (-5850 4800);
FORCEPROP 1 LAST NEEDS_NO_SIZE TRUE
J 0
(-5850 4800);
DISPLAY 0.723404 (-5850 4800);
PAINT GREEN (-5850 4800);
DISPLAY INVISIBLE (-5850 4800);
FORCEPROP 1 LAST CDS_LMAN_SYM_OUTLINE -300,700,250,-650
J 0
(-5850 4800);
DISPLAY 0.468085 (-5850 4800);
PAINT GREEN (-5850 4800);
DISPLAY INVISIBLE (-5850 4800);
FORCEPROP 1 LAST PATH I38
J 0
(-5850 4800);
DISPLAY 0.723404 (-5850 4800);
PAINT GREEN (-5850 4800);
DISPLAY INVISIBLE (-5850 4800);
FORCEPROP 1 LAST PART_NUMBER AL099390004
J 0
(-6150 5600);
DISPLAY 0.489362 (-6150 5600);
PAINT SKYBLUE (-6150 5600);
DISPLAY INVISIBLE (-6150 5600);
FORCEADD UNIVERSAL_GND..1
(-7000 5400);
FORCEPROP 3 LASTPIN (-7000 5450) SIG_NAME GND\g
J 0
(-6990 5460);
DISPLAY 0.659574 (-6990 5460);
PAINT MONO (-6990 5460);
DISPLAY INVISIBLE (-6990 5460);
FORCEPROP 2 LAST CDS_LIB pure_quanta_power
J 0
(-7000 5400);
DISPLAY INVISIBLE (-7000 5400);
FORCEPROP 1 LAST HDL_POWER GND
J 1
(-6975 5325);
DISPLAY 0.872340 (-6975 5325);
PAINT GREEN (-6975 5325);
DISPLAY INVISIBLE (-6975 5325);
FORCEPROP 1 LAST PATH I39
J 0
(-6925 5400);
DISPLAY 0.872340 (-6925 5400);
PAINT AQUA (-6925 5400);
DISPLAY INVISIBLE (-6925 5400);
FORCEADD UNIVERSAL_GND..1
(-7275 1025);
FORCEPROP 3 LASTPIN (-7275 1075) SIG_NAME GND\g
J 0
(-7265 1085);
DISPLAY 0.659574 (-7265 1085);
PAINT MONO (-7265 1085);
DISPLAY INVISIBLE (-7265 1085);
FORCEPROP 2 LAST CDS_LIB pure_quanta_power
J 0
(-7275 1025);
DISPLAY INVISIBLE (-7275 1025);
FORCEPROP 1 LAST HDL_POWER GND
J 1
(-7250 950);
DISPLAY 0.872340 (-7250 950);
PAINT GREEN (-7250 950);
DISPLAY INVISIBLE (-7250 950);
FORCEPROP 1 LAST PATH I4
J 0
(-7200 1025);
DISPLAY 0.872340 (-7200 1025);
PAINT AQUA (-7200 1025);
DISPLAY INVISIBLE (-7200 1025);
FORCEADD Q_CAP..1
(-7000 5650);
FORCEPROP 1 LAST LOCATION PC548_C0P0_3
J 0
(-6950 5750);
DISPLAY 0.489362 (-6950 5750);
PAINT SKYBLUE (-6950 5750);
FORCEPROP 0 LAST $SEC 1
J 0
(-6950 5800);
DISPLAY 0.680851 (-6950 5800);
PAINT MONO (-6950 5800);
DISPLAY INVISIBLE (-6950 5800);
FORCEPROP 0 LAST CDS_SEC 1
J 0
(-6950 5800);
DISPLAY 1.021277 (-6950 5800);
DISPLAY INVISIBLE (-6950 5800);
FORCEPROP 1 LASTPIN (-7000 5750) $PN 1
J 0
(-6990 5730);
DISPLAY 0.489362 (-6990 5730);
PAINT MONO (-6990 5730);
FORCEPROP 1 LASTPIN (-7000 5550) $PN 2
J 0
(-6990 5530);
DISPLAY 0.489362 (-6990 5530);
PAINT MONO (-6990 5530);
FORCEPROP 1 LAST MATERIAL X6S
J 0
(-6950 5550);
DISPLAY 0.489362 (-6950 5550);
PAINT SKYBLUE (-6950 5550);
FORCEPROP 1 LAST TOLERANCE 10%
J 0
(-6950 5600);
DISPLAY 0.489362 (-6950 5600);
PAINT SKYBLUE (-6950 5600);
FORCEPROP 1 LAST VALUE 2.2UF
J 0
(-6950 5700);
DISPLAY 0.489362 (-6950 5700);
PAINT SKYBLUE (-6950 5700);
FORCEPROP 1 LAST VOLTAGE 10V
J 0
(-6950 5650);
DISPLAY 0.489362 (-6950 5650);
PAINT SKYBLUE (-6950 5650);
FORCEPROP 1 LAST PACK_TYPE C0402
J 0
(-6950 5450);
DISPLAY 0.489362 (-6950 5450);
PAINT SKYBLUE (-6950 5450);
FORCEPROP 2 LAST CDS_LIB pure_quanta
J 0
(-7000 5650);
DISPLAY INVISIBLE (-7000 5650);
FORCEPROP 1 LAST PATH I40
J 0
(-6950 5800);
DISPLAY 0.978723 (-6950 5800);
PAINT WHITE (-6950 5800);
DISPLAY INVISIBLE (-6950 5800);
FORCEPROP 1 LAST PART_NUMBER CH5222KEB01
J 0
(-6950 5500);
DISPLAY 0.489362 (-6950 5500);
PAINT SKYBLUE (-6950 5500);
DISPLAY INVISIBLE (-6950 5500);
FORCEADD VCC_CORE..1
(-7350 6100);
FORCEPROP 3 LASTPIN (-7350 6050) SIG_NAME PVDDCR_CPU0_P0_PVCC\g
J 0
(-7340 6060);
DISPLAY 0.659574 (-7340 6060);
PAINT MONO (-7340 6060);
DISPLAY INVISIBLE (-7340 6060);
FORCEPROP 1 LAST HDL_POWER PVDDCR_CPU0_P0_PVCC
J 1
(-7350 6150);
DISPLAY 0.489362 (-7350 6150);
PAINT GREEN (-7350 6150);
FORCEPROP 2 LAST CDS_LIB pure_quanta_power
J 0
(-7350 6100);
DISPLAY INVISIBLE (-7350 6100);
FORCEPROP 1 LAST PATH I41
J 0
(-7300 6125);
DISPLAY 0.872340 (-7300 6125);
PAINT AQUA (-7300 6125);
DISPLAY INVISIBLE (-7300 6125);
FORCEADD UNIVERSAL_GND..1
(-5300 4025);
FORCEPROP 3 LASTPIN (-5300 4075) SIG_NAME GND\g
J 0
(-5290 4085);
DISPLAY 0.659574 (-5290 4085);
PAINT MONO (-5290 4085);
DISPLAY INVISIBLE (-5290 4085);
FORCEPROP 2 LAST CDS_LIB pure_quanta_power
J 0
(-5300 4025);
DISPLAY INVISIBLE (-5300 4025);
FORCEPROP 1 LAST HDL_POWER GND
J 1
(-5275 3950);
DISPLAY 0.872340 (-5275 3950);
PAINT GREEN (-5275 3950);
DISPLAY INVISIBLE (-5275 3950);
FORCEPROP 1 LAST PATH I42
J 0
(-5225 4025);
DISPLAY 0.872340 (-5225 4025);
PAINT AQUA (-5225 4025);
DISPLAY INVISIBLE (-5225 4025);
FORCEADD Q_CAP..1
(-5225 5700);
FORCEPROP 1 LAST LOCATION PC552_3
J 0
(-5175 5800);
DISPLAY 0.489362 (-5175 5800);
PAINT SKYBLUE (-5175 5800);
FORCEPROP 0 LAST $SEC 1
J 0
(-5175 5850);
DISPLAY 0.680851 (-5175 5850);
PAINT MONO (-5175 5850);
DISPLAY INVISIBLE (-5175 5850);
FORCEPROP 0 LAST CDS_SEC 1
J 0
(-5175 5850);
DISPLAY 1.021277 (-5175 5850);
DISPLAY INVISIBLE (-5175 5850);
FORCEPROP 1 LASTPIN (-5225 5800) $PN 1
J 0
(-5215 5780);
DISPLAY 0.489362 (-5215 5780);
PAINT MONO (-5215 5780);
FORCEPROP 1 LASTPIN (-5225 5600) $PN 2
J 0
(-5215 5580);
DISPLAY 0.489362 (-5215 5580);
PAINT MONO (-5215 5580);
FORCEPROP 1 LAST TOLERANCE 10%
J 0
(-5175 5650);
DISPLAY 0.489362 (-5175 5650);
PAINT SKYBLUE (-5175 5650);
FORCEPROP 1 LAST VOLTAGE 25V
J 0
(-5175 5700);
DISPLAY 0.489362 (-5175 5700);
PAINT SKYBLUE (-5175 5700);
FORCEPROP 1 LAST PACK_TYPE 0402
J 0
(-5175 5500);
DISPLAY 0.489362 (-5175 5500);
PAINT SKYBLUE (-5175 5500);
FORCEPROP 1 LAST VALUE 0.1UF
J 0
(-5175 5750);
DISPLAY 0.489362 (-5175 5750);
PAINT SKYBLUE (-5175 5750);
FORCEPROP 1 LAST MATERIAL X7R
J 0
(-5175 5600);
DISPLAY 0.489362 (-5175 5600);
PAINT SKYBLUE (-5175 5600);
FORCEPROP 2 LAST CDS_LIB pure_quanta
J 0
(-5225 5700);
DISPLAY INVISIBLE (-5225 5700);
FORCEPROP 1 LAST PATH I43
J 0
(-5175 5850);
DISPLAY 0.978723 (-5175 5850);
PAINT WHITE (-5175 5850);
DISPLAY INVISIBLE (-5175 5850);
FORCEPROP 1 LAST PART_NUMBER CH4104K1B00
J 0
(-5175 5550);
DISPLAY 0.489362 (-5175 5550);
PAINT SKYBLUE (-5175 5550);
DISPLAY INVISIBLE (-5175 5550);
FORCEADD Q_RES..2
(-4375 4150);
FORCEPROP 1 LAST LOCATION PR498
J 0
(-4330 4275);
DISPLAY 0.489362 (-4330 4275);
PAINT SKYBLUE (-4330 4275);
FORCEPROP 0 LAST $SEC 1
J 0
(-4325 4325);
DISPLAY 0.680851 (-4325 4325);
PAINT MONO (-4325 4325);
DISPLAY INVISIBLE (-4325 4325);
FORCEPROP 0 LAST CDS_SEC 1
J 0
(-4325 4325);
DISPLAY 1.021277 (-4325 4325);
DISPLAY INVISIBLE (-4325 4325);
FORCEPROP 1 LASTPIN (-4375 4250) $PN 1
J 0
(-4370 4212);
DISPLAY 0.489362 (-4370 4212);
PAINT MONO (-4370 4212);
FORCEPROP 1 LASTPIN (-4375 4050) $PN 2
J 0
(-4370 4060);
DISPLAY 0.489362 (-4370 4060);
PAINT MONO (-4370 4060);
FORCEPROP 1 LAST WATTAGE 1/8W
J 0
(-4335 4125);
DISPLAY 0.489362 (-4335 4125);
PAINT SKYBLUE (-4335 4125);
FORCEPROP 1 LAST MATERIAL EMPTY
J 0
(-4335 4075);
DISPLAY 0.489362 (-4335 4075);
PAINT RED (-4335 4075);
FORCEPROP 1 LAST VALUE 1.5
J 0
(-4330 4225);
DISPLAY 0.489362 (-4330 4225);
PAINT SKYBLUE (-4330 4225);
FORCEPROP 1 LAST PACK_TYPE 0402LF
J 0
(-4335 3975);
DISPLAY 0.489362 (-4335 3975);
PAINT SKYBLUE (-4335 3975);
FORCEPROP 1 LAST TOLERANCE 1%
J 0
(-4330 4175);
DISPLAY 0.489362 (-4330 4175);
PAINT SKYBLUE (-4330 4175);
FORCEPROP 2 LAST CDS_LIB pure_quanta
J 0
(-4375 4150);
DISPLAY INVISIBLE (-4375 4150);
FORCEPROP 1 LAST PATH I44
J 0
(-4325 4325);
DISPLAY 0.978723 (-4325 4325);
PAINT WHITE (-4325 4325);
DISPLAY INVISIBLE (-4325 4325);
FORCEPROP 1 LAST PART_NUMBER CS-1504FB00
J 0
(-4335 4025);
DISPLAY 0.489362 (-4335 4025);
PAINT SKYBLUE (-4335 4025);
DISPLAY INVISIBLE (-4335 4025);
FORCEADD Q_CAP..1
(-4375 4625);
FORCEPROP 1 LAST LOCATION PC180
J 0
(-4325 4725);
DISPLAY 0.489362 (-4325 4725);
PAINT SKYBLUE (-4325 4725);
FORCEPROP 0 LAST $SEC 1
J 0
(-4325 4775);
DISPLAY 0.680851 (-4325 4775);
PAINT MONO (-4325 4775);
DISPLAY INVISIBLE (-4325 4775);
FORCEPROP 0 LAST CDS_SEC 1
J 0
(-4325 4775);
DISPLAY 1.021277 (-4325 4775);
DISPLAY INVISIBLE (-4325 4775);
FORCEPROP 1 LASTPIN (-4375 4725) $PN 1
J 0
(-4365 4705);
DISPLAY 0.489362 (-4365 4705);
PAINT MONO (-4365 4705);
FORCEPROP 1 LASTPIN (-4375 4525) $PN 2
J 0
(-4365 4505);
DISPLAY 0.489362 (-4365 4505);
PAINT MONO (-4365 4505);
FORCEPROP 1 LAST VOLTAGE 50V
J 0
(-4325 4625);
DISPLAY 0.489362 (-4325 4625);
PAINT SKYBLUE (-4325 4625);
FORCEPROP 1 LAST PACK_TYPE C0402
J 0
(-4325 4425);
DISPLAY 0.489362 (-4325 4425);
PAINT SKYBLUE (-4325 4425);
FORCEPROP 1 LAST MATERIAL EMPTY
J 0
(-4325 4525);
DISPLAY 0.489362 (-4325 4525);
PAINT RED (-4325 4525);
FORCEPROP 1 LAST TOLERANCE 10%
J 0
(-4325 4575);
DISPLAY 0.489362 (-4325 4575);
PAINT SKYBLUE (-4325 4575);
FORCEPROP 1 LAST VALUE 560PF
J 0
(-4325 4675);
DISPLAY 0.489362 (-4325 4675);
PAINT SKYBLUE (-4325 4675);
FORCEPROP 2 LAST CDS_LIB pure_quanta
J 0
(-4375 4625);
DISPLAY INVISIBLE (-4375 4625);
FORCEPROP 1 LAST PATH I45
J 0
(-4325 4775);
DISPLAY 0.978723 (-4325 4775);
PAINT WHITE (-4325 4775);
DISPLAY INVISIBLE (-4325 4775);
FORCEPROP 1 LAST PART_NUMBER CH1566K1B09
J 0
(-4325 4475);
DISPLAY 0.489362 (-4325 4475);
PAINT SKYBLUE (-4325 4475);
DISPLAY INVISIBLE (-4325 4475);
FORCEADD Q_RES..1
(-4450 5150);
FORCEPROP 1 LAST LOCATION PR348
J 0
(-4500 5200);
DISPLAY 0.489362 (-4500 5200);
PAINT SKYBLUE (-4500 5200);
FORCEPROP 0 LAST $SEC 1
J 0
(-4425 5225);
DISPLAY 0.680851 (-4425 5225);
PAINT MONO (-4425 5225);
DISPLAY INVISIBLE (-4425 5225);
FORCEPROP 0 LAST CDS_SEC 1
J 0
(-4425 5225);
DISPLAY 1.021277 (-4425 5225);
DISPLAY INVISIBLE (-4425 5225);
FORCEPROP 1 LASTPIN (-4550 5150) $PN 1
J 0
(-4538 5162);
DISPLAY 0.489362 (-4538 5162);
PAINT MONO (-4538 5162);
FORCEPROP 1 LASTPIN (-4350 5150) $PN 2
J 0
(-4388 5162);
DISPLAY 0.489362 (-4388 5162);
PAINT MONO (-4388 5162);
FORCEPROP 1 LAST WATTAGE 1/16W
J 0
(-4350 5100);
DISPLAY 0.489362 (-4350 5100);
PAINT SKYBLUE (-4350 5100);
FORCEPROP 1 LAST PACK_TYPE 0402LF
J 0
(-4350 5050);
DISPLAY 0.489362 (-4350 5050);
PAINT SKYBLUE (-4350 5050);
FORCEPROP 1 LAST TOLERANCE 1%
J 0
(-4325 5175);
DISPLAY 0.489362 (-4325 5175);
PAINT SKYBLUE (-4325 5175);
FORCEPROP 1 LAST MATERIAL CHIP
J 0
(-4700 5050);
DISPLAY 0.489362 (-4700 5050);
PAINT SKYBLUE (-4700 5050);
FORCEPROP 1 LAST VALUE 5.6
J 2
(-4575 5175);
DISPLAY 0.489362 (-4575 5175);
PAINT SKYBLUE (-4575 5175);
FORCEPROP 2 LAST CDS_LIB pure_quanta
J 0
(-4450 5150);
DISPLAY INVISIBLE (-4450 5150);
FORCEPROP 1 LAST PATH I46
J 0
(-4500 5300);
DISPLAY 0.978723 (-4500 5300);
PAINT WHITE (-4500 5300);
DISPLAY INVISIBLE (-4500 5300);
FORCEPROP 1 LAST PART_NUMBER CS-5602FB01
J 0
(-4700 5100);
DISPLAY 0.489362 (-4700 5100);
PAINT SKYBLUE (-4700 5100);
DISPLAY INVISIBLE (-4700 5100);
FORCEADD Q_CAP..1
(-4875 5700);
FORCEPROP 1 LAST LOCATION PC550_3
J 0
(-4825 5800);
DISPLAY 0.489362 (-4825 5800);
PAINT SKYBLUE (-4825 5800);
FORCEPROP 0 LAST $SEC 1
J 0
(-4825 5825);
DISPLAY 0.680851 (-4825 5825);
PAINT MONO (-4825 5825);
DISPLAY INVISIBLE (-4825 5825);
FORCEPROP 0 LAST CDS_SEC 1
J 0
(-4825 5825);
DISPLAY 1.021277 (-4825 5825);
DISPLAY INVISIBLE (-4825 5825);
FORCEPROP 1 LASTPIN (-4875 5800) $PN 1
J 0
(-4865 5780);
DISPLAY 0.489362 (-4865 5780);
PAINT MONO (-4865 5780);
FORCEPROP 1 LASTPIN (-4875 5600) $PN 2
J 0
(-4865 5580);
DISPLAY 0.489362 (-4865 5580);
PAINT MONO (-4865 5580);
FORCEPROP 1 LAST PACK_TYPE C0402
J 0
(-4825 5500);
DISPLAY 0.489362 (-4825 5500);
PAINT SKYBLUE (-4825 5500);
FORCEPROP 1 LAST MATERIAL X6S
J 0
(-4825 5600);
DISPLAY 0.489362 (-4825 5600);
PAINT SKYBLUE (-4825 5600);
FORCEPROP 1 LAST TOLERANCE 10%
J 0
(-4825 5650);
DISPLAY 0.489362 (-4825 5650);
PAINT SKYBLUE (-4825 5650);
FORCEPROP 1 LAST VALUE 1UF
J 0
(-4825 5750);
DISPLAY 0.489362 (-4825 5750);
PAINT SKYBLUE (-4825 5750);
FORCEPROP 1 LAST VOLTAGE 25V
J 0
(-4825 5700);
DISPLAY 0.489362 (-4825 5700);
PAINT SKYBLUE (-4825 5700);
FORCEPROP 2 LAST CDS_LIB pure_quanta
J 0
(-4875 5700);
DISPLAY INVISIBLE (-4875 5700);
FORCEPROP 1 LAST PATH I47
J 0
(-4825 5850);
DISPLAY 0.978723 (-4825 5850);
PAINT WHITE (-4825 5850);
DISPLAY INVISIBLE (-4825 5850);
FORCEPROP 1 LAST PART_NUMBER CH5104KEB02
J 0
(-4825 5550);
DISPLAY 0.489362 (-4825 5550);
PAINT SKYBLUE (-4825 5550);
DISPLAY INVISIBLE (-4825 5550);
FORCEADD Q_CAP..1
(-4550 5700);
FORCEPROP 1 LAST LOCATION PC554_3
J 0
(-4500 5800);
DISPLAY 0.489362 (-4500 5800);
PAINT SKYBLUE (-4500 5800);
FORCEPROP 0 LAST $SEC 1
J 0
(-4500 5825);
DISPLAY 0.680851 (-4500 5825);
PAINT MONO (-4500 5825);
DISPLAY INVISIBLE (-4500 5825);
FORCEPROP 0 LAST CDS_SEC 1
J 0
(-4500 5825);
DISPLAY 1.021277 (-4500 5825);
DISPLAY INVISIBLE (-4500 5825);
FORCEPROP 1 LASTPIN (-4550 5800) $PN 1
J 0
(-4540 5780);
DISPLAY 0.489362 (-4540 5780);
PAINT MONO (-4540 5780);
FORCEPROP 1 LASTPIN (-4550 5600) $PN 2
J 0
(-4540 5580);
DISPLAY 0.489362 (-4540 5580);
PAINT MONO (-4540 5580);
FORCEPROP 1 LAST MATERIAL X6S
J 0
(-4500 5600);
DISPLAY 0.489362 (-4500 5600);
PAINT SKYBLUE (-4500 5600);
FORCEPROP 1 LAST PACK_TYPE C0805
J 0
(-4500 5500);
DISPLAY 0.489362 (-4500 5500);
PAINT SKYBLUE (-4500 5500);
FORCEPROP 1 LAST VOLTAGE 16V
J 0
(-4500 5700);
DISPLAY 0.489362 (-4500 5700);
PAINT SKYBLUE (-4500 5700);
FORCEPROP 1 LAST TOLERANCE 20%
J 0
(-4500 5650);
DISPLAY 0.489362 (-4500 5650);
PAINT SKYBLUE (-4500 5650);
FORCEPROP 1 LAST VALUE 22UF
J 0
(-4500 5750);
DISPLAY 0.489362 (-4500 5750);
PAINT SKYBLUE (-4500 5750);
FORCEPROP 2 LAST CDS_LIB pure_quanta
J 0
(-4550 5700);
DISPLAY INVISIBLE (-4550 5700);
FORCEPROP 1 LAST PATH I48
J 0
(-4500 5850);
DISPLAY 0.978723 (-4500 5850);
PAINT WHITE (-4500 5850);
DISPLAY INVISIBLE (-4500 5850);
FORCEPROP 1 LAST PART_NUMBER CH6223MEA01
J 0
(-4500 5550);
DISPLAY 0.489362 (-4500 5550);
PAINT SKYBLUE (-4500 5550);
DISPLAY INVISIBLE (-4500 5550);
FORCEADD Q_CAP..1
(-4225 5700);
FORCEPROP 1 LAST LOCATION PC556_3
J 0
(-4175 5800);
DISPLAY 0.489362 (-4175 5800);
PAINT SKYBLUE (-4175 5800);
FORCEPROP 0 LAST $SEC 1
J 0
(-4175 5825);
DISPLAY 0.680851 (-4175 5825);
PAINT MONO (-4175 5825);
DISPLAY INVISIBLE (-4175 5825);
FORCEPROP 0 LAST CDS_SEC 1
J 0
(-4175 5825);
DISPLAY 1.021277 (-4175 5825);
DISPLAY INVISIBLE (-4175 5825);
FORCEPROP 1 LASTPIN (-4225 5800) $PN 1
J 0
(-4215 5780);
DISPLAY 0.489362 (-4215 5780);
PAINT MONO (-4215 5780);
FORCEPROP 1 LASTPIN (-4225 5600) $PN 2
J 0
(-4215 5580);
DISPLAY 0.489362 (-4215 5580);
PAINT MONO (-4215 5580);
FORCEPROP 1 LAST PACK_TYPE C0805
J 0
(-4175 5500);
DISPLAY 0.489362 (-4175 5500);
PAINT SKYBLUE (-4175 5500);
FORCEPROP 1 LAST VOLTAGE 16V
J 0
(-4175 5700);
DISPLAY 0.489362 (-4175 5700);
PAINT SKYBLUE (-4175 5700);
FORCEPROP 1 LAST VALUE 22UF
J 0
(-4175 5750);
DISPLAY 0.489362 (-4175 5750);
PAINT SKYBLUE (-4175 5750);
FORCEPROP 1 LAST MATERIAL X6S
J 0
(-4175 5600);
DISPLAY 0.489362 (-4175 5600);
PAINT SKYBLUE (-4175 5600);
FORCEPROP 1 LAST TOLERANCE 20%
J 0
(-4175 5650);
DISPLAY 0.489362 (-4175 5650);
PAINT SKYBLUE (-4175 5650);
FORCEPROP 2 LAST CDS_LIB pure_quanta
J 0
(-4225 5700);
DISPLAY INVISIBLE (-4225 5700);
FORCEPROP 1 LAST PATH I49
J 0
(-4175 5850);
DISPLAY 0.978723 (-4175 5850);
PAINT WHITE (-4175 5850);
DISPLAY INVISIBLE (-4175 5850);
FORCEPROP 1 LAST PART_NUMBER CH6223MEA01
J 0
(-4175 5550);
DISPLAY 0.489362 (-4175 5550);
PAINT SKYBLUE (-4175 5550);
DISPLAY INVISIBLE (-4175 5550);
FORCEADD UNIVERSAL_GND..1
(-7250 1650);
FORCEPROP 3 LASTPIN (-7250 1700) SIG_NAME GND\g
J 0
(-7240 1710);
DISPLAY 0.659574 (-7240 1710);
PAINT MONO (-7240 1710);
DISPLAY INVISIBLE (-7240 1710);
FORCEPROP 2 LAST CDS_LIB pure_quanta_power
J 0
(-7250 1650);
DISPLAY INVISIBLE (-7250 1650);
FORCEPROP 1 LAST HDL_POWER GND
J 1
(-7225 1575);
DISPLAY 0.872340 (-7225 1575);
PAINT GREEN (-7225 1575);
DISPLAY INVISIBLE (-7225 1575);
FORCEPROP 1 LAST PATH I5
J 0
(-7175 1650);
DISPLAY 0.872340 (-7175 1650);
PAINT AQUA (-7175 1650);
DISPLAY INVISIBLE (-7175 1650);
FORCEADD Q_RES..1
(-3875 600);
FORCEPROP 1 LAST LOCATION PR351
J 0
(-3900 650);
DISPLAY 0.489362 (-3900 650);
PAINT SKYBLUE (-3900 650);
FORCEPROP 0 LAST $SEC 1
J 0
(-3875 675);
DISPLAY 0.680851 (-3875 675);
PAINT MONO (-3875 675);
DISPLAY INVISIBLE (-3875 675);
FORCEPROP 0 LAST CDS_SEC 1
J 0
(-3875 675);
DISPLAY 1.021277 (-3875 675);
DISPLAY INVISIBLE (-3875 675);
FORCEPROP 1 LASTPIN (-3975 600) $PN 1
J 0
(-3963 612);
DISPLAY 0.489362 (-3963 612);
PAINT MONO (-3963 612);
FORCEPROP 1 LASTPIN (-3775 600) $PN 2
J 0
(-3813 612);
DISPLAY 0.489362 (-3813 612);
PAINT MONO (-3813 612);
FORCEPROP 1 LAST PACK_TYPE 0402LF
J 0
(-3775 500);
DISPLAY 0.489362 (-3775 500);
PAINT SKYBLUE (-3775 500);
FORCEPROP 1 LAST VALUE 0
J 2
(-4000 625);
DISPLAY 0.489362 (-4000 625);
PAINT SKYBLUE (-4000 625);
FORCEPROP 1 LAST TOLERANCE 5%
J 0
(-3750 625);
DISPLAY 0.489362 (-3750 625);
PAINT SKYBLUE (-3750 625);
FORCEPROP 1 LAST MATERIAL CHIP
J 0
(-4125 500);
DISPLAY 0.489362 (-4125 500);
PAINT SKYBLUE (-4125 500);
FORCEPROP 1 LAST WATTAGE 1/16W
J 0
(-3775 550);
DISPLAY 0.489362 (-3775 550);
PAINT SKYBLUE (-3775 550);
FORCEPROP 2 LAST CDS_LIB pure_quanta
J 0
(-3875 600);
DISPLAY INVISIBLE (-3875 600);
FORCEPROP 1 LAST PATH I50
J 0
(-3925 750);
DISPLAY 0.978723 (-3925 750);
PAINT WHITE (-3925 750);
DISPLAY INVISIBLE (-3925 750);
FORCEPROP 1 LAST PART_NUMBER CS00002JB13
J 0
(-4125 550);
DISPLAY 0.489362 (-4125 550);
PAINT SKYBLUE (-4125 550);
DISPLAY INVISIBLE (-4125 550);
FORCEADD OFFPAGE..3
R 2
(-3575 1250);
FORCEPROP 2 LAST $XR0 195 
J 0
(-3855 1250);
DISPLAY 0.638298 (-3855 1250);
PAINT MONO (-3855 1250);
FORCEPROP 2 LAST CDS_LIB standard
J 2
(-3575 1250);
DISPLAY INVISIBLE (-3575 1250);
FORCEPROP 1 LAST OFFPAGE TRUE
J 2
(-3900 1125);
DISPLAY 0.872340 (-3900 1125);
PAINT GREEN (-3900 1125);
DISPLAY INVISIBLE (-3900 1125);
FORCEPROP 1 LAST COMMENT_BODY TRUE
J 2
(-3525 1150);
DISPLAY 0.872340 (-3525 1150);
PAINT GREEN (-3525 1150);
DISPLAY INVISIBLE (-3525 1150);
FORCEPROP 2 LAST PATH I51
J 0
(-3875 1300);
DISPLAY 0.680851 (-3875 1300);
DISPLAY INVISIBLE (-3875 1300);
FORCEADD Q_INDUCTOR4P_14..1
(-2700 1375);
FORCEPROP 1 LAST LOCATION PL60
J 0
(-2925 1630);
DISPLAY 0.489362 (-2925 1630);
PAINT SKYBLUE (-2925 1630);
FORCEPROP 0 LAST $SEC 1
J 0
(-2925 1775);
DISPLAY 0.680851 (-2925 1775);
PAINT MONO (-2925 1775);
DISPLAY INVISIBLE (-2925 1775);
FORCEPROP 0 LAST CDS_SEC 1
J 0
(-2925 1775);
DISPLAY 1.021277 (-2925 1775);
DISPLAY INVISIBLE (-2925 1775);
FORCEPROP 0 LASTPIN (-3100 1500) $PN 1
J 2
(-3110 1510);
DISPLAY 0.489362 (-3110 1510);
PAINT MONO (-3110 1510);
FORCEPROP 0 LASTPIN (-3100 1250) $PN 2
J 2
(-3110 1260);
DISPLAY 0.489362 (-3110 1260);
PAINT MONO (-3110 1260);
FORCEPROP 0 LASTPIN (-2300 1250) $PN 3
J 0
(-2290 1260);
DISPLAY 0.489362 (-2290 1260);
PAINT MONO (-2290 1260);
FORCEPROP 0 LASTPIN (-2300 1500) $PN 4
J 0
(-2290 1510);
DISPLAY 0.489362 (-2290 1510);
PAINT MONO (-2290 1510);
FORCEPROP 2 LAST PART_TYPE SMLF
J 0
(-2925 1725);
DISPLAY 1.021277 (-2925 1725);
FORCEPROP 1 LAST MATERIAL IND
J 0
(-2925 1585);
DISPLAY 0.489362 (-2925 1585);
PAINT SKYBLUE (-2925 1585);
FORCEPROP 2 LAST VALUE 150NH
J 0
(-2925 1675);
DISPLAY 0.489362 (-2925 1675);
PAINT SKYBLUE (-2925 1675);
FORCEPROP 2 LAST CDS_LIB pure_quanta
J 0
(-2700 1375);
DISPLAY INVISIBLE (-2700 1375);
FORCEPROP 1 LAST NEEDS_NO_SIZE TRUE
J 0
(-2700 1375);
DISPLAY 0.468085 (-2700 1375);
PAINT GREEN (-2700 1375);
DISPLAY INVISIBLE (-2700 1375);
FORCEPROP 1 LAST PATH I52
J 0
(-2500 1530);
DISPLAY 0.723404 (-2500 1530);
PAINT GREEN (-2500 1530);
DISPLAY INVISIBLE (-2500 1530);
FORCEPROP 1 LAST PART_NUMBER CV+15^0TZ04
J 0
(-2925 1535);
DISPLAY 0.489362 (-2925 1535);
PAINT SKYBLUE (-2925 1535);
DISPLAY INVISIBLE (-2925 1535);
FORCEADD Q_CAP..1
(-3400 1725);
FORCEPROP 1 LAST LOCATION PC561
J 0
(-3350 1850);
DISPLAY 0.489362 (-3350 1850);
PAINT SKYBLUE (-3350 1850);
FORCEPROP 0 LAST $SEC 1
J 0
(-3350 1875);
DISPLAY 0.680851 (-3350 1875);
PAINT MONO (-3350 1875);
DISPLAY INVISIBLE (-3350 1875);
FORCEPROP 0 LAST CDS_SEC 1
J 0
(-3350 1875);
DISPLAY 1.021277 (-3350 1875);
DISPLAY INVISIBLE (-3350 1875);
FORCEPROP 1 LASTPIN (-3400 1825) $PN 1
J 0
(-3390 1805);
DISPLAY 0.489362 (-3390 1805);
PAINT MONO (-3390 1805);
FORCEPROP 1 LASTPIN (-3400 1625) $PN 2
J 0
(-3390 1605);
DISPLAY 0.489362 (-3390 1605);
PAINT MONO (-3390 1605);
FORCEPROP 1 LAST MATERIAL X7R
J 0
(-3350 1650);
DISPLAY 0.489362 (-3350 1650);
PAINT SKYBLUE (-3350 1650);
FORCEPROP 1 LAST TOLERANCE 10%
J 0
(-3350 1700);
DISPLAY 0.489362 (-3350 1700);
PAINT SKYBLUE (-3350 1700);
FORCEPROP 1 LAST VALUE 0.22UF
J 0
(-3350 1800);
DISPLAY 0.489362 (-3350 1800);
PAINT SKYBLUE (-3350 1800);
FORCEPROP 1 LAST VOLTAGE 16V
J 0
(-3350 1750);
DISPLAY 0.489362 (-3350 1750);
PAINT SKYBLUE (-3350 1750);
FORCEPROP 1 LAST PACK_TYPE 0402
J 0
(-3350 1550);
DISPLAY 0.489362 (-3350 1550);
PAINT SKYBLUE (-3350 1550);
FORCEPROP 2 LAST CDS_LIB pure_quanta
J 0
(-3400 1725);
DISPLAY INVISIBLE (-3400 1725);
FORCEPROP 1 LAST PATH I53
J 0
(-3350 1875);
DISPLAY 0.978723 (-3350 1875);
PAINT WHITE (-3350 1875);
DISPLAY INVISIBLE (-3350 1875);
FORCEPROP 1 LAST PART_NUMBER CH4223K1B00
J 0
(-3350 1600);
DISPLAY 0.489362 (-3350 1600);
PAINT SKYBLUE (-3350 1600);
DISPLAY INVISIBLE (-3350 1600);
FORCEADD UNIVERSAL_GND..1
(-3700 2050);
FORCEPROP 3 LASTPIN (-3700 2100) SIG_NAME GND\g
J 0
(-3690 2110);
DISPLAY 0.659574 (-3690 2110);
PAINT MONO (-3690 2110);
DISPLAY INVISIBLE (-3690 2110);
FORCEPROP 2 LAST CDS_LIB pure_quanta_power
J 0
(-3700 2050);
DISPLAY INVISIBLE (-3700 2050);
FORCEPROP 1 LAST HDL_POWER GND
J 1
(-3675 1975);
DISPLAY 0.872340 (-3675 1975);
PAINT GREEN (-3675 1975);
DISPLAY INVISIBLE (-3675 1975);
FORCEPROP 1 LAST PATH I54
J 0
(-3625 2050);
DISPLAY 0.872340 (-3625 2050);
PAINT AQUA (-3625 2050);
DISPLAY INVISIBLE (-3625 2050);
FORCEADD Q_CAP..1
(-3700 2400);
FORCEPROP 1 LAST LOCATION PC559_4
J 0
(-3650 2500);
DISPLAY 0.489362 (-3650 2500);
PAINT SKYBLUE (-3650 2500);
FORCEPROP 0 LAST $SEC 1
J 0
(-3650 2525);
DISPLAY 0.680851 (-3650 2525);
PAINT MONO (-3650 2525);
DISPLAY INVISIBLE (-3650 2525);
FORCEPROP 0 LAST CDS_SEC 1
J 0
(-3650 2525);
DISPLAY 1.021277 (-3650 2525);
DISPLAY INVISIBLE (-3650 2525);
FORCEPROP 1 LASTPIN (-3700 2500) $PN 1
J 0
(-3690 2480);
DISPLAY 0.489362 (-3690 2480);
PAINT MONO (-3690 2480);
FORCEPROP 1 LASTPIN (-3700 2300) $PN 2
J 0
(-3690 2280);
DISPLAY 0.489362 (-3690 2280);
PAINT MONO (-3690 2280);
FORCEPROP 1 LAST MATERIAL X6S
J 0
(-3650 2300);
DISPLAY 0.489362 (-3650 2300);
PAINT SKYBLUE (-3650 2300);
FORCEPROP 1 LAST VALUE 22UF
J 0
(-3650 2450);
DISPLAY 0.489362 (-3650 2450);
PAINT SKYBLUE (-3650 2450);
FORCEPROP 1 LAST VOLTAGE 16V
J 0
(-3650 2400);
DISPLAY 0.489362 (-3650 2400);
PAINT SKYBLUE (-3650 2400);
FORCEPROP 1 LAST TOLERANCE 20%
J 0
(-3650 2350);
DISPLAY 0.489362 (-3650 2350);
PAINT SKYBLUE (-3650 2350);
FORCEPROP 1 LAST PACK_TYPE C0805
J 0
(-3650 2200);
DISPLAY 0.489362 (-3650 2200);
PAINT SKYBLUE (-3650 2200);
FORCEPROP 2 LAST CDS_LIB pure_quanta
J 0
(-3700 2400);
DISPLAY INVISIBLE (-3700 2400);
FORCEPROP 1 LAST PATH I55
J 0
(-3650 2550);
DISPLAY 0.978723 (-3650 2550);
PAINT WHITE (-3650 2550);
DISPLAY INVISIBLE (-3650 2550);
FORCEPROP 1 LAST PART_NUMBER CH6223MEA01
J 0
(-3650 2250);
DISPLAY 0.489362 (-3650 2250);
PAINT SKYBLUE (-3650 2250);
DISPLAY INVISIBLE (-3650 2250);
FORCEADD VCC_CORE..1
(-3700 2700);
FORCEPROP 3 LASTPIN (-3700 2650) SIG_NAME SW_P12V_AUX_PVDDCR_CPU0_P0_FLT\g
J 0
(-3690 2660);
DISPLAY 0.659574 (-3690 2660);
PAINT MONO (-3690 2660);
DISPLAY INVISIBLE (-3690 2660);
FORCEPROP 1 LAST HDL_POWER SW_P12V_AUX_PVDDCR_CPU0_P0_FLT
J 1
(-3700 2750);
DISPLAY 0.489362 (-3700 2750);
PAINT GREEN (-3700 2750);
FORCEPROP 2 LAST CDS_LIB pure_quanta_power
J 0
(-3700 2700);
DISPLAY INVISIBLE (-3700 2700);
FORCEPROP 1 LAST PATH I56
J 0
(-3650 2725);
DISPLAY 0.872340 (-3650 2725);
PAINT AQUA (-3650 2725);
DISPLAY INVISIBLE (-3650 2725);
FORCEADD UNIVERSAL_GND..1
(-1875 1050);
FORCEPROP 3 LASTPIN (-1875 1100) SIG_NAME GND\g
J 0
(-1865 1110);
DISPLAY 0.659574 (-1865 1110);
PAINT MONO (-1865 1110);
DISPLAY INVISIBLE (-1865 1110);
FORCEPROP 2 LAST CDS_LIB pure_quanta_power
J 0
(-1875 1050);
DISPLAY INVISIBLE (-1875 1050);
FORCEPROP 1 LAST HDL_POWER GND
J 1
(-1850 975);
DISPLAY 0.872340 (-1850 975);
PAINT GREEN (-1850 975);
DISPLAY INVISIBLE (-1850 975);
FORCEPROP 1 LAST PATH I57
J 0
(-1800 1050);
DISPLAY 0.872340 (-1800 1050);
PAINT AQUA (-1800 1050);
DISPLAY INVISIBLE (-1800 1050);
FORCEADD Q_CAP..1
(-1300 1325);
FORCEPROP 1 LAST LOCATION PC563_4
J 0
(-1250 1425);
DISPLAY 0.489362 (-1250 1425);
PAINT SKYBLUE (-1250 1425);
FORCEPROP 0 LAST $SEC 1
J 0
(-1250 1450);
DISPLAY 0.680851 (-1250 1450);
PAINT MONO (-1250 1450);
DISPLAY INVISIBLE (-1250 1450);
FORCEPROP 0 LAST CDS_SEC 1
J 0
(-1250 1450);
DISPLAY 1.021277 (-1250 1450);
DISPLAY INVISIBLE (-1250 1450);
FORCEPROP 1 LASTPIN (-1300 1425) $PN 1
J 0
(-1290 1405);
DISPLAY 0.489362 (-1290 1405);
PAINT MONO (-1290 1405);
FORCEPROP 1 LASTPIN (-1300 1225) $PN 2
J 0
(-1290 1205);
DISPLAY 0.489362 (-1290 1205);
PAINT MONO (-1290 1205);
FORCEPROP 1 LAST VOLTAGE 4V
J 0
(-1250 1325);
DISPLAY 0.489362 (-1250 1325);
PAINT SKYBLUE (-1250 1325);
FORCEPROP 1 LAST VALUE 22UF
J 0
(-1250 1375);
DISPLAY 0.489362 (-1250 1375);
PAINT SKYBLUE (-1250 1375);
FORCEPROP 1 LAST TOLERANCE 20%
J 0
(-1250 1275);
DISPLAY 0.489362 (-1250 1275);
PAINT SKYBLUE (-1250 1275);
FORCEPROP 1 LAST MATERIAL X6S
J 0
(-1250 1225);
DISPLAY 0.489362 (-1250 1225);
PAINT SKYBLUE (-1250 1225);
FORCEPROP 1 LAST PACK_TYPE C0805
J 0
(-1250 1125);
DISPLAY 0.489362 (-1250 1125);
PAINT SKYBLUE (-1250 1125);
FORCEPROP 2 LAST CDS_LIB pure_quanta
J 0
(-1300 1325);
DISPLAY INVISIBLE (-1300 1325);
FORCEPROP 1 LAST PATH I58
J 0
(-1250 1475);
DISPLAY 0.978723 (-1250 1475);
PAINT WHITE (-1250 1475);
DISPLAY INVISIBLE (-1250 1475);
FORCEPROP 1 LAST PART_NUMBER CH622KMEA03
J 0
(-1250 1175);
DISPLAY 0.489362 (-1250 1175);
PAINT SKYBLUE (-1250 1175);
DISPLAY INVISIBLE (-1250 1175);
FORCEADD UNIVERSAL_GND..1
(-800 825);
FORCEPROP 3 LASTPIN (-800 875) SIG_NAME GND\g
J 0
(-790 885);
DISPLAY 0.659574 (-790 885);
PAINT MONO (-790 885);
DISPLAY INVISIBLE (-790 885);
FORCEPROP 2 LAST CDS_LIB pure_quanta_power
J 0
(-800 825);
DISPLAY INVISIBLE (-800 825);
FORCEPROP 1 LAST HDL_POWER GND
J 1
(-775 750);
DISPLAY 0.872340 (-775 750);
PAINT GREEN (-775 750);
DISPLAY INVISIBLE (-775 750);
FORCEPROP 1 LAST PATH I59
J 0
(-725 825);
DISPLAY 0.872340 (-725 825);
PAINT AQUA (-725 825);
DISPLAY INVISIBLE (-725 825);
FORCEADD Q_CAP..1
(-7250 1850);
FORCEPROP 1 LAST LOCATION PC547
J 0
(-7200 1950);
DISPLAY 0.489362 (-7200 1950);
PAINT SKYBLUE (-7200 1950);
FORCEPROP 0 LAST $SEC 1
J 0
(-7200 2000);
DISPLAY 0.680851 (-7200 2000);
PAINT MONO (-7200 2000);
DISPLAY INVISIBLE (-7200 2000);
FORCEPROP 0 LAST CDS_SEC 1
J 0
(-7200 2000);
DISPLAY 1.021277 (-7200 2000);
DISPLAY INVISIBLE (-7200 2000);
FORCEPROP 1 LASTPIN (-7250 1950) $PN 1
J 0
(-7240 1930);
DISPLAY 0.489362 (-7240 1930);
PAINT MONO (-7240 1930);
FORCEPROP 1 LASTPIN (-7250 1750) $PN 2
J 0
(-7240 1730);
DISPLAY 0.489362 (-7240 1730);
PAINT MONO (-7240 1730);
FORCEPROP 1 LAST MATERIAL X6S
J 0
(-7200 1750);
DISPLAY 0.489362 (-7200 1750);
PAINT SKYBLUE (-7200 1750);
FORCEPROP 1 LAST TOLERANCE 10%
J 0
(-7200 1800);
DISPLAY 0.489362 (-7200 1800);
PAINT SKYBLUE (-7200 1800);
FORCEPROP 1 LAST VALUE 2.2UF
J 0
(-7200 1900);
DISPLAY 0.489362 (-7200 1900);
PAINT SKYBLUE (-7200 1900);
FORCEPROP 1 LAST VOLTAGE 10V
J 0
(-7200 1850);
DISPLAY 0.489362 (-7200 1850);
PAINT SKYBLUE (-7200 1850);
FORCEPROP 1 LAST PACK_TYPE C0402
J 0
(-7200 1650);
DISPLAY 0.489362 (-7200 1650);
PAINT SKYBLUE (-7200 1650);
FORCEPROP 2 LAST CDS_LIB pure_quanta
J 0
(-7250 1850);
DISPLAY INVISIBLE (-7250 1850);
FORCEPROP 1 LAST PATH I6
J 0
(-7200 2000);
DISPLAY 0.978723 (-7200 2000);
PAINT WHITE (-7200 2000);
DISPLAY INVISIBLE (-7200 2000);
FORCEPROP 1 LAST PART_NUMBER CH5222KEB01
J 0
(-7200 1700);
DISPLAY 0.489362 (-7200 1700);
PAINT SKYBLUE (-7200 1700);
DISPLAY INVISIBLE (-7200 1700);
FORCEADD Q_CAP..1
(-800 1325);
FORCEPROP 1 LAST LOCATION PC565_4
J 0
(-750 1425);
DISPLAY 0.489362 (-750 1425);
PAINT SKYBLUE (-750 1425);
FORCEPROP 0 LAST $SEC 1
J 0
(-750 1450);
DISPLAY 0.680851 (-750 1450);
PAINT MONO (-750 1450);
DISPLAY INVISIBLE (-750 1450);
FORCEPROP 0 LAST CDS_SEC 1
J 0
(-750 1450);
DISPLAY 1.021277 (-750 1450);
DISPLAY INVISIBLE (-750 1450);
FORCEPROP 1 LASTPIN (-800 1425) $PN 1
J 0
(-790 1405);
DISPLAY 0.489362 (-790 1405);
PAINT MONO (-790 1405);
FORCEPROP 1 LASTPIN (-800 1225) $PN 2
J 0
(-790 1205);
DISPLAY 0.489362 (-790 1205);
PAINT MONO (-790 1205);
FORCEPROP 1 LAST VOLTAGE 4V
J 0
(-750 1325);
DISPLAY 0.489362 (-750 1325);
PAINT SKYBLUE (-750 1325);
FORCEPROP 1 LAST VALUE 22UF
J 0
(-750 1375);
DISPLAY 0.489362 (-750 1375);
PAINT SKYBLUE (-750 1375);
FORCEPROP 1 LAST TOLERANCE 20%
J 0
(-750 1275);
DISPLAY 0.489362 (-750 1275);
PAINT SKYBLUE (-750 1275);
FORCEPROP 1 LAST MATERIAL X6S
J 0
(-750 1225);
DISPLAY 0.489362 (-750 1225);
PAINT SKYBLUE (-750 1225);
FORCEPROP 1 LAST PACK_TYPE C0805
J 0
(-750 1125);
DISPLAY 0.489362 (-750 1125);
PAINT SKYBLUE (-750 1125);
FORCEPROP 2 LAST CDS_LIB pure_quanta
J 0
(-800 1325);
DISPLAY INVISIBLE (-800 1325);
FORCEPROP 1 LAST PATH I60
J 0
(-750 1475);
DISPLAY 0.978723 (-750 1475);
PAINT WHITE (-750 1475);
DISPLAY INVISIBLE (-750 1475);
FORCEPROP 1 LAST PART_NUMBER CH622KMEA03
J 0
(-750 1175);
DISPLAY 0.489362 (-750 1175);
PAINT SKYBLUE (-750 1175);
DISPLAY INVISIBLE (-750 1175);
FORCEADD VCC_CORE..1
(-800 1650);
FORCEPROP 3 LASTPIN (-800 1600) SIG_NAME PVDDCR_CPU0_P0\g
J 0
(-790 1610);
DISPLAY 0.659574 (-790 1610);
PAINT MONO (-790 1610);
DISPLAY INVISIBLE (-790 1610);
FORCEPROP 1 LAST HDL_POWER PVDDCR_CPU0_P0
J 1
(-800 1700);
DISPLAY 0.489362 (-800 1700);
PAINT GREEN (-800 1700);
FORCEPROP 2 LAST CDS_LIB pure_quanta_power
J 0
(-800 1650);
DISPLAY INVISIBLE (-800 1650);
FORCEPROP 1 LAST PATH I61
J 0
(-750 1675);
DISPLAY 0.872340 (-750 1675);
PAINT AQUA (-750 1675);
DISPLAY INVISIBLE (-750 1675);
FORCEADD OFFPAGE..3
R 2
(-3675 4550);
FORCEPROP 2 LAST $XR0 194 
J 0
(-3985 4550);
DISPLAY 0.638298 (-3985 4550);
PAINT MONO (-3985 4550);
FORCEPROP 2 LAST CDS_LIB standard
J 2
(-3675 4550);
DISPLAY INVISIBLE (-3675 4550);
FORCEPROP 1 LAST OFFPAGE TRUE
J 2
(-4000 4425);
DISPLAY 0.872340 (-4000 4425);
PAINT GREEN (-4000 4425);
DISPLAY INVISIBLE (-4000 4425);
FORCEPROP 1 LAST COMMENT_BODY TRUE
J 2
(-3625 4450);
DISPLAY 0.872340 (-3625 4450);
PAINT GREEN (-3625 4450);
DISPLAY INVISIBLE (-3625 4450);
FORCEPROP 2 LAST PATH I62
J 0
(-3975 4600);
DISPLAY 0.680851 (-3975 4600);
DISPLAY INVISIBLE (-3975 4600);
FORCEADD Q_CAP..1
(-3450 5025);
FORCEPROP 1 LAST LOCATION PC560
J 0
(-3400 5150);
DISPLAY 0.489362 (-3400 5150);
PAINT SKYBLUE (-3400 5150);
FORCEPROP 0 LAST $SEC 1
J 0
(-3400 5175);
DISPLAY 0.680851 (-3400 5175);
PAINT MONO (-3400 5175);
DISPLAY INVISIBLE (-3400 5175);
FORCEPROP 0 LAST CDS_SEC 1
J 0
(-3400 5175);
DISPLAY 1.021277 (-3400 5175);
DISPLAY INVISIBLE (-3400 5175);
FORCEPROP 1 LASTPIN (-3450 5125) $PN 1
J 0
(-3440 5105);
DISPLAY 0.489362 (-3440 5105);
PAINT MONO (-3440 5105);
FORCEPROP 1 LASTPIN (-3450 4925) $PN 2
J 0
(-3440 4905);
DISPLAY 0.489362 (-3440 4905);
PAINT MONO (-3440 4905);
FORCEPROP 1 LAST MATERIAL X7R
J 0
(-3400 4950);
DISPLAY 0.489362 (-3400 4950);
PAINT SKYBLUE (-3400 4950);
FORCEPROP 1 LAST TOLERANCE 10%
J 0
(-3400 5000);
DISPLAY 0.489362 (-3400 5000);
PAINT SKYBLUE (-3400 5000);
FORCEPROP 1 LAST VALUE 0.22UF
J 0
(-3400 5100);
DISPLAY 0.489362 (-3400 5100);
PAINT SKYBLUE (-3400 5100);
FORCEPROP 1 LAST VOLTAGE 16V
J 0
(-3400 5050);
DISPLAY 0.489362 (-3400 5050);
PAINT SKYBLUE (-3400 5050);
FORCEPROP 1 LAST PACK_TYPE 0402
J 0
(-3400 4850);
DISPLAY 0.489362 (-3400 4850);
PAINT SKYBLUE (-3400 4850);
FORCEPROP 2 LAST CDS_LIB pure_quanta
J 0
(-3450 5025);
DISPLAY INVISIBLE (-3450 5025);
FORCEPROP 1 LAST PATH I63
J 0
(-3400 5175);
DISPLAY 0.978723 (-3400 5175);
PAINT WHITE (-3400 5175);
DISPLAY INVISIBLE (-3400 5175);
FORCEPROP 1 LAST PART_NUMBER CH4223K1B00
J 0
(-3400 4900);
DISPLAY 0.489362 (-3400 4900);
PAINT SKYBLUE (-3400 4900);
DISPLAY INVISIBLE (-3400 4900);
FORCEADD Q_INDUCTOR4P_14..1
(-2725 4675);
FORCEPROP 1 LAST LOCATION PL59
J 0
(-2950 4930);
DISPLAY 0.489362 (-2950 4930);
PAINT SKYBLUE (-2950 4930);
FORCEPROP 0 LAST $SEC 1
J 0
(-2950 5075);
DISPLAY 0.680851 (-2950 5075);
PAINT MONO (-2950 5075);
DISPLAY INVISIBLE (-2950 5075);
FORCEPROP 0 LAST CDS_SEC 1
J 0
(-2950 5075);
DISPLAY 1.021277 (-2950 5075);
DISPLAY INVISIBLE (-2950 5075);
FORCEPROP 0 LASTPIN (-3125 4800) $PN 1
J 2
(-3135 4810);
DISPLAY 0.489362 (-3135 4810);
PAINT MONO (-3135 4810);
FORCEPROP 0 LASTPIN (-3125 4550) $PN 2
J 2
(-3135 4560);
DISPLAY 0.489362 (-3135 4560);
PAINT MONO (-3135 4560);
FORCEPROP 0 LASTPIN (-2325 4550) $PN 3
J 0
(-2315 4560);
DISPLAY 0.489362 (-2315 4560);
PAINT MONO (-2315 4560);
FORCEPROP 0 LASTPIN (-2325 4800) $PN 4
J 0
(-2315 4810);
DISPLAY 0.489362 (-2315 4810);
PAINT MONO (-2315 4810);
FORCEPROP 2 LAST PART_TYPE SMLF
J 0
(-2950 5025);
DISPLAY 1.021277 (-2950 5025);
FORCEPROP 1 LAST MATERIAL IND
J 0
(-2950 4885);
DISPLAY 0.489362 (-2950 4885);
PAINT SKYBLUE (-2950 4885);
FORCEPROP 2 LAST VALUE 150NH
J 0
(-2950 4975);
DISPLAY 0.489362 (-2950 4975);
PAINT SKYBLUE (-2950 4975);
FORCEPROP 2 LAST CDS_LIB pure_quanta
J 0
(-2725 4675);
DISPLAY INVISIBLE (-2725 4675);
FORCEPROP 1 LAST NEEDS_NO_SIZE TRUE
J 0
(-2725 4675);
DISPLAY 0.468085 (-2725 4675);
PAINT GREEN (-2725 4675);
DISPLAY INVISIBLE (-2725 4675);
FORCEPROP 1 LAST PATH I64
J 0
(-2525 4830);
DISPLAY 0.723404 (-2525 4830);
PAINT GREEN (-2525 4830);
DISPLAY INVISIBLE (-2525 4830);
FORCEPROP 1 LAST PART_NUMBER CV+15^0TZ04
J 0
(-2950 4835);
DISPLAY 0.489362 (-2950 4835);
PAINT SKYBLUE (-2950 4835);
DISPLAY INVISIBLE (-2950 4835);
FORCEADD UNIVERSAL_GND..1
(-3925 5375);
FORCEPROP 3 LASTPIN (-3925 5425) SIG_NAME GND\g
J 0
(-3915 5435);
DISPLAY 0.659574 (-3915 5435);
PAINT MONO (-3915 5435);
DISPLAY INVISIBLE (-3915 5435);
FORCEPROP 2 LAST CDS_LIB pure_quanta_power
J 0
(-3925 5375);
DISPLAY INVISIBLE (-3925 5375);
FORCEPROP 1 LAST HDL_POWER GND
J 1
(-3900 5300);
DISPLAY 0.872340 (-3900 5300);
PAINT GREEN (-3900 5300);
DISPLAY INVISIBLE (-3900 5300);
FORCEPROP 1 LAST PATH I65
J 0
(-3850 5375);
DISPLAY 0.872340 (-3850 5375);
PAINT AQUA (-3850 5375);
DISPLAY INVISIBLE (-3850 5375);
FORCEADD Q_CAP..1
(-3925 5700);
FORCEPROP 1 LAST LOCATION PC558_3
J 0
(-3875 5800);
DISPLAY 0.489362 (-3875 5800);
PAINT SKYBLUE (-3875 5800);
FORCEPROP 0 LAST $SEC 1
J 0
(-3875 5825);
DISPLAY 0.680851 (-3875 5825);
PAINT MONO (-3875 5825);
DISPLAY INVISIBLE (-3875 5825);
FORCEPROP 0 LAST CDS_SEC 1
J 0
(-3875 5825);
DISPLAY 1.021277 (-3875 5825);
DISPLAY INVISIBLE (-3875 5825);
FORCEPROP 1 LASTPIN (-3925 5800) $PN 1
J 0
(-3915 5780);
DISPLAY 0.489362 (-3915 5780);
PAINT MONO (-3915 5780);
FORCEPROP 1 LASTPIN (-3925 5600) $PN 2
J 0
(-3915 5580);
DISPLAY 0.489362 (-3915 5580);
PAINT MONO (-3915 5580);
FORCEPROP 1 LAST MATERIAL X6S
J 0
(-3875 5600);
DISPLAY 0.489362 (-3875 5600);
PAINT SKYBLUE (-3875 5600);
FORCEPROP 1 LAST PACK_TYPE C0805
J 0
(-3875 5500);
DISPLAY 0.489362 (-3875 5500);
PAINT SKYBLUE (-3875 5500);
FORCEPROP 1 LAST TOLERANCE 20%
J 0
(-3875 5650);
DISPLAY 0.489362 (-3875 5650);
PAINT SKYBLUE (-3875 5650);
FORCEPROP 1 LAST VALUE 22UF
J 0
(-3875 5750);
DISPLAY 0.489362 (-3875 5750);
PAINT SKYBLUE (-3875 5750);
FORCEPROP 1 LAST VOLTAGE 16V
J 0
(-3875 5700);
DISPLAY 0.489362 (-3875 5700);
PAINT SKYBLUE (-3875 5700);
FORCEPROP 2 LAST CDS_LIB pure_quanta
J 0
(-3925 5700);
DISPLAY INVISIBLE (-3925 5700);
FORCEPROP 1 LAST PATH I66
J 0
(-3875 5850);
DISPLAY 0.978723 (-3875 5850);
PAINT WHITE (-3875 5850);
DISPLAY INVISIBLE (-3875 5850);
FORCEPROP 1 LAST PART_NUMBER CH6223MEA01
J 0
(-3875 5550);
DISPLAY 0.489362 (-3875 5550);
PAINT SKYBLUE (-3875 5550);
DISPLAY INVISIBLE (-3875 5550);
FORCEADD VCC_CORE..1
(-3925 6000);
FORCEPROP 3 LASTPIN (-3925 5950) SIG_NAME SW_P12V_AUX_PVDDCR_CPU0_P0_FLT\g
J 0
(-3915 5960);
DISPLAY 0.659574 (-3915 5960);
PAINT MONO (-3915 5960);
DISPLAY INVISIBLE (-3915 5960);
FORCEPROP 1 LAST HDL_POWER SW_P12V_AUX_PVDDCR_CPU0_P0_FLT
J 1
(-3925 6050);
DISPLAY 0.489362 (-3925 6050);
PAINT GREEN (-3925 6050);
FORCEPROP 2 LAST CDS_LIB pure_quanta_power
J 0
(-3925 6000);
DISPLAY INVISIBLE (-3925 6000);
FORCEPROP 1 LAST PATH I67
J 0
(-3875 6025);
DISPLAY 0.872340 (-3875 6025);
PAINT AQUA (-3875 6025);
DISPLAY INVISIBLE (-3875 6025);
FORCEADD OFFPAGE..3
(-1850 4550);
FORCEPROP 2 LAST $XR0 195 
J 0
(-1576 4550);
DISPLAY 0.638298 (-1576 4550);
PAINT MONO (-1576 4550);
FORCEPROP 2 LAST CDS_LIB standard
J 2
(-1850 4550);
DISPLAY INVISIBLE (-1850 4550);
FORCEPROP 1 LAST OFFPAGE TRUE
J 0
(-1525 4425);
DISPLAY 0.872340 (-1525 4425);
PAINT GREEN (-1525 4425);
DISPLAY INVISIBLE (-1525 4425);
FORCEPROP 1 LAST COMMENT_BODY TRUE
J 0
(-1900 4450);
DISPLAY 0.872340 (-1900 4450);
PAINT GREEN (-1900 4450);
DISPLAY INVISIBLE (-1900 4450);
FORCEPROP 2 LAST PATH I68
J 0
(-1575 4600);
DISPLAY 0.680851 (-1575 4600);
DISPLAY INVISIBLE (-1575 4600);
FORCEADD UNIVERSAL_GND..1
(-975 4275);
FORCEPROP 3 LASTPIN (-975 4325) SIG_NAME GND\g
J 0
(-965 4335);
DISPLAY 0.659574 (-965 4335);
PAINT MONO (-965 4335);
DISPLAY INVISIBLE (-965 4335);
FORCEPROP 2 LAST CDS_LIB pure_quanta_power
J 0
(-975 4275);
DISPLAY INVISIBLE (-975 4275);
FORCEPROP 1 LAST HDL_POWER GND
J 1
(-950 4200);
DISPLAY 0.872340 (-950 4200);
PAINT GREEN (-950 4200);
DISPLAY INVISIBLE (-950 4200);
FORCEPROP 1 LAST PATH I69
J 0
(-900 4275);
DISPLAY 0.872340 (-900 4275);
PAINT AQUA (-900 4275);
DISPLAY INVISIBLE (-900 4275);
FORCEADD OFFPAGE..2
R 2
(-6925 1500);
FORCEPROP 2 LAST $XR0 193 
J 0
(-7180 1500);
DISPLAY 0.638298 (-7180 1500);
PAINT MONO (-7180 1500);
FORCEPROP 2 LAST CDS_LIB standard
J 2
(-6925 1500);
DISPLAY INVISIBLE (-6925 1500);
FORCEPROP 1 LAST OFFPAGE TRUE
J 2
(-7250 1375);
DISPLAY 0.872340 (-7250 1375);
PAINT GREEN (-7250 1375);
DISPLAY INVISIBLE (-7250 1375);
FORCEPROP 1 LAST COMMENT_BODY TRUE
J 2
(-6880 1405);
DISPLAY 0.872340 (-6880 1405);
PAINT GREEN (-6880 1405);
DISPLAY INVISIBLE (-6880 1405);
FORCEPROP 2 LAST PATH I7
J 0
(-7175 1550);
DISPLAY 0.680851 (-7175 1550);
DISPLAY INVISIBLE (-7175 1550);
FORCEADD Q_CAP..1
(-1400 4625);
FORCEPROP 1 LAST LOCATION PC562_3
J 0
(-1350 4725);
DISPLAY 0.489362 (-1350 4725);
PAINT SKYBLUE (-1350 4725);
FORCEPROP 0 LAST $SEC 1
J 0
(-1350 4750);
DISPLAY 0.680851 (-1350 4750);
PAINT MONO (-1350 4750);
DISPLAY INVISIBLE (-1350 4750);
FORCEPROP 0 LAST CDS_SEC 1
J 0
(-1350 4750);
DISPLAY 1.021277 (-1350 4750);
DISPLAY INVISIBLE (-1350 4750);
FORCEPROP 1 LASTPIN (-1400 4725) $PN 1
J 0
(-1390 4705);
DISPLAY 0.489362 (-1390 4705);
PAINT MONO (-1390 4705);
FORCEPROP 1 LASTPIN (-1400 4525) $PN 2
J 0
(-1390 4505);
DISPLAY 0.489362 (-1390 4505);
PAINT MONO (-1390 4505);
FORCEPROP 1 LAST VOLTAGE 4V
J 0
(-1350 4625);
DISPLAY 0.489362 (-1350 4625);
PAINT SKYBLUE (-1350 4625);
FORCEPROP 1 LAST VALUE 22UF
J 0
(-1350 4675);
DISPLAY 0.489362 (-1350 4675);
PAINT SKYBLUE (-1350 4675);
FORCEPROP 1 LAST TOLERANCE 20%
J 0
(-1350 4575);
DISPLAY 0.489362 (-1350 4575);
PAINT SKYBLUE (-1350 4575);
FORCEPROP 1 LAST MATERIAL X6S
J 0
(-1350 4525);
DISPLAY 0.489362 (-1350 4525);
PAINT SKYBLUE (-1350 4525);
FORCEPROP 1 LAST PACK_TYPE C0805
J 0
(-1350 4425);
DISPLAY 0.489362 (-1350 4425);
PAINT SKYBLUE (-1350 4425);
FORCEPROP 2 LAST CDS_LIB pure_quanta
J 0
(-1400 4625);
DISPLAY INVISIBLE (-1400 4625);
FORCEPROP 1 LAST PATH I70
J 0
(-1350 4775);
DISPLAY 0.978723 (-1350 4775);
PAINT WHITE (-1350 4775);
DISPLAY INVISIBLE (-1350 4775);
FORCEPROP 1 LAST PART_NUMBER CH622KMEA03
J 0
(-1350 4475);
DISPLAY 0.489362 (-1350 4475);
PAINT SKYBLUE (-1350 4475);
DISPLAY INVISIBLE (-1350 4475);
FORCEADD Q_CAP..1
(-975 4625);
FORCEPROP 1 LAST LOCATION PC564_3
J 0
(-925 4725);
DISPLAY 0.489362 (-925 4725);
PAINT SKYBLUE (-925 4725);
FORCEPROP 0 LAST $SEC 1
J 0
(-925 4750);
DISPLAY 0.680851 (-925 4750);
PAINT MONO (-925 4750);
DISPLAY INVISIBLE (-925 4750);
FORCEPROP 0 LAST CDS_SEC 1
J 0
(-925 4750);
DISPLAY 1.021277 (-925 4750);
DISPLAY INVISIBLE (-925 4750);
FORCEPROP 1 LASTPIN (-975 4725) $PN 1
J 0
(-965 4705);
DISPLAY 0.489362 (-965 4705);
PAINT MONO (-965 4705);
FORCEPROP 1 LASTPIN (-975 4525) $PN 2
J 0
(-965 4505);
DISPLAY 0.489362 (-965 4505);
PAINT MONO (-965 4505);
FORCEPROP 1 LAST VOLTAGE 4V
J 0
(-925 4625);
DISPLAY 0.489362 (-925 4625);
PAINT SKYBLUE (-925 4625);
FORCEPROP 1 LAST VALUE 22UF
J 0
(-925 4675);
DISPLAY 0.489362 (-925 4675);
PAINT SKYBLUE (-925 4675);
FORCEPROP 1 LAST TOLERANCE 20%
J 0
(-925 4575);
DISPLAY 0.489362 (-925 4575);
PAINT SKYBLUE (-925 4575);
FORCEPROP 1 LAST MATERIAL X6S
J 0
(-925 4525);
DISPLAY 0.489362 (-925 4525);
PAINT SKYBLUE (-925 4525);
FORCEPROP 1 LAST PACK_TYPE C0805
J 0
(-925 4425);
DISPLAY 0.489362 (-925 4425);
PAINT SKYBLUE (-925 4425);
FORCEPROP 2 LAST CDS_LIB pure_quanta
J 0
(-975 4625);
DISPLAY INVISIBLE (-975 4625);
FORCEPROP 1 LAST PATH I71
J 0
(-925 4775);
DISPLAY 0.978723 (-925 4775);
PAINT WHITE (-925 4775);
DISPLAY INVISIBLE (-925 4775);
FORCEPROP 1 LAST PART_NUMBER CH622KMEA03
J 0
(-925 4475);
DISPLAY 0.489362 (-925 4475);
PAINT SKYBLUE (-925 4475);
DISPLAY INVISIBLE (-925 4475);
FORCEADD VCC_CORE..1
(-975 4950);
FORCEPROP 3 LASTPIN (-975 4900) SIG_NAME PVDDCR_CPU0_P0\g
J 0
(-965 4910);
DISPLAY 0.659574 (-965 4910);
PAINT MONO (-965 4910);
DISPLAY INVISIBLE (-965 4910);
FORCEPROP 1 LAST HDL_POWER PVDDCR_CPU0_P0
J 1
(-975 5000);
DISPLAY 0.489362 (-975 5000);
PAINT GREEN (-975 5000);
FORCEPROP 2 LAST CDS_LIB pure_quanta_power
J 0
(-975 4950);
DISPLAY INVISIBLE (-975 4950);
FORCEPROP 1 LAST PATH I72
J 0
(-925 4975);
DISPLAY 0.872340 (-925 4975);
PAINT AQUA (-925 4975);
DISPLAY INVISIBLE (-925 4975);
FORCEADD OFFPAGE..1
(-6875 900);
FORCEPROP 2 LAST $XR0 193 
J 0
(-7127 900);
DISPLAY 0.638298 (-7127 900);
PAINT MONO (-7127 900);
FORCEPROP 2 LAST CDS_LIB standard
J 2
(-6875 900);
DISPLAY INVISIBLE (-6875 900);
FORCEPROP 1 LAST OFFPAGE TRUE
J 0
(-6550 775);
DISPLAY 0.872340 (-6550 775);
PAINT GREEN (-6550 775);
DISPLAY INVISIBLE (-6550 775);
FORCEPROP 1 LAST COMMENT_BODY TRUE
J 0
(-6750 800);
DISPLAY 0.872340 (-6750 800);
PAINT GREEN (-6750 800);
DISPLAY INVISIBLE (-6750 800);
FORCEPROP 2 LAST PATH I8
J 0
(-7125 950);
DISPLAY 0.680851 (-7125 950);
DISPLAY INVISIBLE (-7125 950);
FORCEADD ISL99390FRZTR5935..1
(-5775 1500);
FORCEPROP 1 LAST LOCATION PU47
J 0
(-6075 2375);
DISPLAY 0.489362 (-6075 2375);
PAINT SKYBLUE (-6075 2375);
FORCEPROP 0 LAST $SEC 1
J 0
(-6075 2525);
DISPLAY 0.680851 (-6075 2525);
PAINT MONO (-6075 2525);
DISPLAY INVISIBLE (-6075 2525);
FORCEPROP 0 LAST CDS_SEC 1
J 0
(-6075 2525);
DISPLAY 1.021277 (-6075 2525);
DISPLAY INVISIBLE (-6075 2525);
FORCEPROP 0 LASTPIN (-5375 1050) $PN 2
J 0
(-5365 1060);
DISPLAY 0.489362 (-5365 1060);
PAINT MONO (-5365 1060);
FORCEPROP 0 LASTPIN (-5375 1850) $PN 33
J 0
(-5365 1860);
DISPLAY 0.489362 (-5365 1860);
PAINT MONO (-5365 1860);
FORCEPROP 0 LASTPIN (-6225 1250) $PN 31
J 2
(-6235 1260);
DISPLAY 0.489362 (-6235 1260);
PAINT MONO (-6235 1260);
FORCEPROP 0 LASTPIN (-6225 1650) $PN 35
J 2
(-6235 1660);
DISPLAY 0.489362 (-6235 1660);
PAINT MONO (-6235 1660);
FORCEPROP 0 LASTPIN (-5375 1200) $PN 6
J 0
(-5365 1210);
DISPLAY 0.489362 (-5365 1210);
PAINT MONO (-5365 1210);
FORCEPROP 0 LASTPIN (-5375 1150) $PN 41
J 0
(-5365 1160);
DISPLAY 0.489362 (-5365 1160);
PAINT MONO (-5365 1160);
FORCEPROP 0 LASTPIN (-6225 1500) $PN 38
J 2
(-6235 1510);
DISPLAY 0.489362 (-6235 1510);
PAINT MONO (-6235 1510);
FORCEPROP 0 LASTPIN (-6225 1200) $PN 37
J 2
(-6235 1210);
DISPLAY 0.489362 (-6235 1210);
PAINT MONO (-6235 1210);
FORCEPROP 0 LASTPIN (-5375 1000) $PN 5
J 0
(-5365 1010);
DISPLAY 0.489362 (-5365 1010);
PAINT MONO (-5365 1010);
FORCEPROP 0 LASTPIN (-5375 950) $PN 7_9-20_24
J 0
(-5365 960);
DISPLAY 0.489362 (-5365 960);
PAINT MONO (-5365 960);
FORCEPROP 0 LASTPIN (-5375 900) $PN 40
J 0
(-5365 910);
DISPLAY 0.489362 (-5365 910);
PAINT MONO (-5365 910);
FORCEPROP 0 LASTPIN (-5375 1600) $PN 32
J 0
(-5365 1610);
DISPLAY 0.489362 (-5365 1610);
PAINT MONO (-5365 1610);
FORCEPROP 0 LASTPIN (-6225 2150) $PN 4
J 2
(-6235 2160);
DISPLAY 0.489362 (-6235 2160);
PAINT MONO (-6235 2160);
FORCEPROP 0 LASTPIN (-6225 900) $PN 34
J 2
(-6235 910);
DISPLAY 0.489362 (-6235 910);
PAINT MONO (-6235 910);
FORCEPROP 0 LASTPIN (-6225 1400) $PN 39
J 2
(-6235 1410);
DISPLAY 0.489362 (-6235 1410);
PAINT MONO (-6235 1410);
FORCEPROP 0 LASTPIN (-5375 1500) $PN 10_19
J 0
(-5365 1510);
DISPLAY 0.489362 (-5365 1510);
PAINT MONO (-5365 1510);
FORCEPROP 0 LASTPIN (-6225 1000) $PN 36
J 2
(-6235 1010);
DISPLAY 0.489362 (-6235 1010);
PAINT MONO (-6235 1010);
FORCEPROP 0 LASTPIN (-6225 1850) $PN 3
J 2
(-6235 1860);
DISPLAY 0.489362 (-6235 1860);
PAINT MONO (-6235 1860);
FORCEPROP 0 LASTPIN (-5375 2150) $PN 25_29
J 0
(-5365 2160);
DISPLAY 0.489362 (-5365 2160);
PAINT MONO (-5365 2160);
FORCEPROP 0 LASTPIN (-5375 2100) $PN 30
J 0
(-5365 2110);
DISPLAY 0.489362 (-5365 2110);
PAINT MONO (-5365 2110);
FORCEPROP 0 LASTPIN (-5375 1250) $PN 1
J 0
(-5365 1260);
DISPLAY 0.489362 (-5365 1260);
PAINT MONO (-5365 1260);
FORCEPROP 2 LAST PART_TYPE SMLF
J 0
(-6075 2475);
DISPLAY 1.021277 (-6075 2475);
FORCEPROP 1 LAST MATERIAL IC
J 0
(-6075 2225);
DISPLAY 0.489362 (-6075 2225);
PAINT SKYBLUE (-6075 2225);
FORCEPROP 2 LAST VALUE ISL99390FRZ-TR5935
J 0
(-6075 2425);
DISPLAY 0.489362 (-6075 2425);
PAINT SKYBLUE (-6075 2425);
FORCEPROP 2 LAST CDS_LIB pure_quanta
J 0
(-5775 1500);
DISPLAY INVISIBLE (-5775 1500);
FORCEPROP 1 LAST NEEDS_NO_SIZE TRUE
J 0
(-5775 1500);
DISPLAY 0.723404 (-5775 1500);
PAINT GREEN (-5775 1500);
DISPLAY INVISIBLE (-5775 1500);
FORCEPROP 1 LAST CDS_LMAN_SYM_OUTLINE -300,700,250,-650
J 0
(-5775 1500);
DISPLAY 0.468085 (-5775 1500);
PAINT GREEN (-5775 1500);
DISPLAY INVISIBLE (-5775 1500);
FORCEPROP 1 LAST PATH I9
J 0
(-5775 1500);
DISPLAY 0.723404 (-5775 1500);
PAINT GREEN (-5775 1500);
DISPLAY INVISIBLE (-5775 1500);
FORCEPROP 1 LAST PART_NUMBER AL099390004
J 0
(-6075 2300);
DISPLAY 0.489362 (-6075 2300);
PAINT SKYBLUE (-6075 2300);
DISPLAY INVISIBLE (-6075 2300);
FORCEADD DNS..1
(-4400 4625);
PAINT RED (-4400 4625);
FORCEPROP 2 LAST CDS_LIB mstr_misc
J 0
(-4400 4625);
DISPLAY INVISIBLE (-4400 4625);
FORCEPROP 1 LAST COMMENT_BODY TRUE
R 1
J 0
(-4325 4400);
DISPLAY 0.872340 (-4325 4400);
PAINT GREEN (-4325 4400);
DISPLAY INVISIBLE (-4325 4400);
FORCEADD DNS..1
(-4400 4150);
PAINT RED (-4400 4150);
FORCEPROP 2 LAST CDS_LIB mstr_misc
J 0
(-4400 4150);
DISPLAY INVISIBLE (-4400 4150);
FORCEPROP 1 LAST COMMENT_BODY TRUE
R 1
J 0
(-4325 3925);
DISPLAY 0.872340 (-4325 3925);
PAINT GREEN (-4325 3925);
DISPLAY INVISIBLE (-4325 3925);
FORCEADD DNS..1
(-7025 4475);
PAINT RED (-7025 4475);
FORCEPROP 2 LAST CDS_LIB mstr_misc
J 0
(-7025 4475);
DISPLAY INVISIBLE (-7025 4475);
FORCEPROP 1 LAST COMMENT_BODY TRUE
R 1
J 0
(-6950 4250);
DISPLAY 0.872340 (-6950 4250);
PAINT GREEN (-6950 4250);
DISPLAY INVISIBLE (-6950 4250);
FORCEADD DNS..1
(-4325 1325);
PAINT RED (-4325 1325);
FORCEPROP 2 LAST CDS_LIB mstr_misc
J 0
(-4325 1325);
DISPLAY INVISIBLE (-4325 1325);
FORCEPROP 1 LAST COMMENT_BODY TRUE
R 1
J 0
(-4250 1100);
DISPLAY 0.872340 (-4250 1100);
PAINT GREEN (-4250 1100);
DISPLAY INVISIBLE (-4250 1100);
FORCEADD DNS..1
(-4325 875);
PAINT RED (-4325 875);
FORCEPROP 2 LAST CDS_LIB mstr_misc
J 0
(-4325 875);
DISPLAY INVISIBLE (-4325 875);
FORCEPROP 1 LAST COMMENT_BODY TRUE
R 1
J 0
(-4250 650);
DISPLAY 0.872340 (-4250 650);
PAINT GREEN (-4250 650);
DISPLAY INVISIBLE (-4250 650);
FORCEADD DNS..1
(-6950 1175);
PAINT RED (-6950 1175);
FORCEPROP 2 LAST CDS_LIB mstr_misc
J 0
(-6950 1175);
DISPLAY INVISIBLE (-6950 1175);
FORCEPROP 1 LAST COMMENT_BODY TRUE
R 1
J 0
(-6875 950);
DISPLAY 0.872340 (-6875 950);
PAINT GREEN (-6875 950);
DISPLAY INVISIBLE (-6875 950);
FORCEADD QUANTA_TITLE_BLOCK_C..1
(0 0);
FORCEPROP 0 LAST CDS_CON_LAST_MODIFIED Thu Sep 14 16:12:18 2023
J 0
(-1885 15);
DISPLAY INVISIBLE (-1885 15);
FORCEPROP 1 LAST CUSTOM_TXT_CDS <CON_LAST_MODIFIED>
J 0
(-1885 15);
DISPLAY 0.978723 (-1885 15);
FORCEPROP 2 LAST CUSTOM_TXT_CDS <XR_PAGE_TITLE>
J 0
(-7890 5250);
DISPLAY 0.638298 (-7890 5250);
PAINT PINK (-7890 5250);
DISPLAY INVISIBLE (-7890 5250);
FORCEPROP 1 LAST CUSTOM_TXT_CDS <NAME_2>
J 0
(-3175 50);
FORCEPROP 1 LAST CUSTOM_TXT_CDS <NAME_1>
J 0
(-3175 175);
FORCEPROP 1 LAST CUSTOM_TXT_CDS <Q_NUMBER>
J 0
(-1403 103);
DISPLAY 1.212766 (-1403 103);
FORCEPROP 1 LAST CUSTOM_TXT_CDS <Q_PROJ>
J 0
(-2382 102);
DISPLAY 1.212766 (-2382 102);
FORCEPROP 1 LAST CUSTOM_TXT_CDS <Q_REV>
J 0
(-184 103);
DISPLAY 1.212766 (-184 103);
FORCEPROP 1 LAST CUSTOM_TXT_CDS <CON_PAGE_NUM> OF <CON_TOTAL_PAGES>
J 0
(-446 18);
DISPLAY 0.978723 (-446 18);
FORCEPROP 1 LAST Q_TITLE PVDDCR_CPU0_P0 VR PHASE 3&4
J 0
(-9325 50);
DISPLAY 2.446809 (-9325 50);
PAINT GREEN (-9325 50);
FORCEPROP 1 LAST CDS_LMAN_SYM_OUTLINE -9475,6775,100,-125
J 0
(0 0);
DISPLAY 0.468085 (0 0);
PAINT GREEN (0 0);
DISPLAY INVISIBLE (0 0);
FORCEPROP 2 LAST CDS_LIB pure_quanta
J 0
(0 0);
DISPLAY INVISIBLE (0 0);
FORCEPROP 2 LAST PAGE_BORDER TRUE
J 0
(-7890 5250);
DISPLAY 0.638298 (-7890 5250);
PAINT PINK (-7890 5250);
DISPLAY INVISIBLE (-7890 5250);
FORCEPROP 2 LAST CDS_XR_PAGE_TITLE CR-195 : @T6G_MB_LIB.T6G(SCH_1):PAGE195
J 0
(-7890 5250);
DISPLAY 0.638298 (-7890 5250);
PAINT PINK (-7890 5250);
DISPLAY INVISIBLE (-7890 5250);
FORCEPROP 1 LAST Q_DEPT BU9
J 1
(-3763 49);
DISPLAY 1.957447 (-3763 49);
PAINT GREEN (-3763 49);
DISPLAY INVISIBLE (-3763 49);
FORCEPROP 1 LAST COMMENT_BODY TRUE
J 0
(12 -13);
DISPLAY 0.978723 (12 -13);
PAINT GREEN (12 -13);
DISPLAY INVISIBLE (12 -13);
WIRE 16 -1 (-6900 2325)(-6900 2200);
WIRE 16 -1 (-4300 775)(-4300 700);
WIRE 16 -1 (-4375 4050)(-4375 3975);
WIRE 16 -1 (-7675 4425)(-7675 4300);
WIRE 16 -1 (-7600 1125)(-7600 1000);
WIRE 16 -1 (-7125 4500)(-7350 4500);
WIRE 16 -1 (-7350 4500)(-7350 4375);
WIRE 16 -1 (-7350 5050)(-7350 5000);
WIRE 16 -1 (-7000 5550)(-7000 5450);
WIRE 16 -1 (-7050 1200)(-7275 1200);
WIRE 16 -1 (-7275 1200)(-7275 1075);
WIRE 16 -1 (-7250 1750)(-7250 1700);
WIRE 16 -1 (-4075 2300)(-4075 2175);
WIRE 16 -1 (-4075 2175)(-3700 2175);
WIRE 16 -1 (-4400 2175)(-4075 2175);
WIRE 16 -1 (-4400 2300)(-4400 2175);
WIRE 16 -1 (-4725 2175)(-4400 2175);
WIRE 16 -1 (-3700 2300)(-3700 2175);
WIRE 16 -1 (-3700 2175)(-3700 2100);
WIRE 16 -1 (-4725 2300)(-4725 2175);
WIRE 16 -1 (-5100 2175)(-4725 2175);
WIRE 16 -1 (-5100 2300)(-5100 2175);
WIRE 16 -1 (-5275 2575)(-5275 2150);
WIRE 16 -1 (-5275 2575)(-5100 2575);
WIRE 16 -1 (-5275 2150)(-5275 2100);
WIRE 16 -1 (-5375 2150)(-5275 2150);
WIRE 16 -1 (-5275 2100)(-5375 2100);
WIRE 16 -1 (-5100 2575)(-4725 2575);
WIRE 16 -1 (-5100 2500)(-5100 2575);
WIRE 16 -1 (-4725 2575)(-4400 2575);
WIRE 16 -1 (-4725 2500)(-4725 2575);
WIRE 16 -1 (-4400 2575)(-4075 2575);
WIRE 16 -1 (-4400 2500)(-4400 2575);
WIRE 16 -1 (-4075 2575)(-3700 2575);
WIRE 16 -1 (-4075 2575)(-4075 2500);
WIRE 16 -1 (-3700 2650)(-3700 2575);
WIRE 16 -1 (-3700 2575)(-3700 2500);
WIRE 16 -1 (-5450 4550)(-4700 4550);
WIRE 16 -1 (-4700 3850)(-4700 4550);
WIRE 16 -1 (-4150 3850)(-4700 3850);
FORCEPROP 2 LAST SIG_NAME PVDDCR_CPU0_P0_VOS3
J 0
(-5335 4575);
DISPLAY 0.489362 (-5335 4575);
FORCEPROP 2 LASTPROP $XRERR UNIQUE?
J 0
(-5575 4575);
DISPLAY 0.638298 (-5575 4575);
PAINT MONO (-5575 4575);
DISPLAY INVISIBLE (-5575 4575);
WIRE 16 -1 (-4375 4800)(-3125 4800);
WIRE 16 -1 (-4375 4800)(-4375 4725);
WIRE 16 -1 (-5450 4800)(-4375 4800);
FORCEPROP 2 LAST SIG_NAME SW_PVDDCR_CPU0_P0_SW3
J 0
(-5335 4810);
DISPLAY 0.489362 (-5335 4810);
FORCEPROP 2 LASTPROP $XRERR UNIQUE?
J 0
(-5575 4810);
DISPLAY 0.638298 (-5575 4810);
PAINT MONO (-5575 4810);
DISPLAY INVISIBLE (-5575 4810);
WIRE 16 -1 (-3450 4925)(-3450 4900);
WIRE 16 -1 (-3450 4900)(-5450 4900);
FORCEPROP 2 LAST SIG_NAME SW_PVDDCR_CPU0_P0_PH3
J 0
(-5335 4910);
DISPLAY 0.489362 (-5335 4910);
FORCEPROP 2 LASTPROP $XRERR UNIQUE?
J 0
(-5575 4910);
DISPLAY 0.638298 (-5575 4910);
PAINT MONO (-5575 4910);
DISPLAY INVISIBLE (-5575 4910);
WIRE 16 -1 (-5450 5150)(-4550 5150);
FORCEPROP 2 LAST SIG_NAME SW_PVDDCR_CPU0_P0_BOOT3
J 0
(-5335 5160);
DISPLAY 0.489362 (-5335 5160);
FORCEPROP 2 LASTPROP $XRERR UNIQUE?
J 0
(-5575 5160);
DISPLAY 0.638298 (-5575 5160);
PAINT MONO (-5575 5160);
DISPLAY INVISIBLE (-5575 5160);
WIRE 16 -1 (-6575 2150)(-6225 2150);
WIRE 16 -1 (-6575 2150)(-6575 2625);
WIRE 16 -1 (-6575 2625)(-6900 2625);
WIRE 16 -1 (-6900 2525)(-6900 2625);
WIRE 16 -1 (-6900 2625)(-7250 2625);
WIRE 16 -1 (-7250 2750)(-7250 2625);
WIRE 16 -1 (-7250 2500)(-7250 2625);
WIRE 16 -1 (-5225 1050)(-5375 1050);
WIRE 16 -1 (-5225 1050)(-5225 1000);
WIRE 16 -1 (-5225 950)(-5225 1000);
WIRE 16 -1 (-5375 1000)(-5225 1000);
WIRE 16 -1 (-5225 900)(-5225 950);
WIRE 16 -1 (-5375 950)(-5225 950);
WIRE 16 -1 (-5225 800)(-5225 900);
WIRE 16 -1 (-5375 900)(-5225 900);
WIRE 16 -1 (-6650 5450)(-6300 5450);
WIRE 16 -1 (-6650 5450)(-6650 5875);
WIRE 16 -1 (-7000 5875)(-6650 5875);
WIRE 16 -1 (-7000 5750)(-7000 5875);
WIRE 16 -1 (-7350 5875)(-7000 5875);
WIRE 16 -1 (-7350 6050)(-7350 5875);
WIRE 16 -1 (-7350 5875)(-7350 5750);
WIRE 16 -1 (-5300 4350)(-5300 4300);
WIRE 16 -1 (-5300 4350)(-5450 4350);
WIRE 16 -1 (-5300 4250)(-5300 4300);
WIRE 16 -1 (-5450 4300)(-5300 4300);
WIRE 16 -1 (-5300 4200)(-5300 4250);
WIRE 16 -1 (-5450 4250)(-5300 4250);
WIRE 16 -1 (-5450 4200)(-5300 4200);
WIRE 16 -1 (-5300 4075)(-5300 4200);
WIRE 16 -1 (-2300 1250)(-1875 1250);
WIRE 16 -1 (-1875 1100)(-1875 1250);
WIRE 16 -1 (-1300 1225)(-1300 1100);
WIRE 16 -1 (-1300 1100)(-800 1100);
WIRE 16 -1 (-800 1225)(-800 1100);
WIRE 16 -1 (-800 875)(-800 1100);
WIRE 16 -1 (-1300 1500)(-1500 1500);
WIRE 16 -1 (-800 1500)(-1300 1500);
WIRE 16 -1 (-1300 1500)(-1300 1425);
WIRE 16 -1 (-1500 1500)(-1500 600);
WIRE 16 -1 (-2300 1500)(-1500 1500);
WIRE 16 -1 (-1500 600)(-3775 600);
WIRE 16 -1 (-800 1600)(-800 1500);
WIRE 16 -1 (-800 1500)(-800 1425);
WIRE 16 -1 (-5225 5600)(-5225 5475);
WIRE 16 -1 (-5225 5475)(-4875 5475);
WIRE 16 -1 (-4875 5475)(-4550 5475);
WIRE 16 -1 (-4875 5600)(-4875 5475);
WIRE 16 -1 (-4550 5475)(-4225 5475);
WIRE 16 -1 (-4550 5600)(-4550 5475);
WIRE 16 -1 (-3925 5475)(-4225 5475);
WIRE 16 -1 (-4225 5600)(-4225 5475);
WIRE 16 -1 (-3925 5600)(-3925 5475);
WIRE 16 -1 (-3925 5475)(-3925 5425);
WIRE 16 -1 (-5450 5400)(-5350 5400);
WIRE 16 -1 (-5350 5450)(-5350 5400);
WIRE 16 -1 (-5350 5875)(-5350 5450);
WIRE 16 -1 (-5450 5450)(-5350 5450);
WIRE 16 -1 (-5350 5875)(-5225 5875);
WIRE 16 -1 (-5225 5875)(-4875 5875);
WIRE 16 -1 (-5225 5800)(-5225 5875);
WIRE 16 -1 (-4875 5875)(-4550 5875);
WIRE 16 -1 (-4875 5800)(-4875 5875);
WIRE 16 -1 (-4550 5875)(-4225 5875);
WIRE 16 -1 (-4550 5800)(-4550 5875);
WIRE 16 -1 (-4225 5875)(-3925 5875);
WIRE 16 -1 (-4225 5875)(-4225 5800);
WIRE 16 -1 (-3925 5950)(-3925 5875);
WIRE 16 -1 (-3925 5875)(-3925 5800);
WIRE 16 -1 (-1400 4525)(-1400 4400);
WIRE 16 -1 (-975 4400)(-1400 4400);
WIRE 16 -1 (-975 4525)(-975 4400);
WIRE 16 -1 (-975 4325)(-975 4400);
WIRE 16 -1 (-1600 4800)(-1400 4800);
WIRE 16 -1 (-2325 4800)(-1600 4800);
WIRE 16 -1 (-1600 4800)(-1600 3850);
WIRE 16 -1 (-1400 4800)(-975 4800);
WIRE 16 -1 (-1400 4725)(-1400 4800);
WIRE 16 -1 (-975 4900)(-975 4800);
WIRE 16 -1 (-975 4800)(-975 4725);
WIRE 16 -1 (-1600 3850)(-3950 3850);
WIRE 16 -1 (-3450 5150)(-3450 5125);
WIRE 16 -1 (-4350 5150)(-3450 5150);
FORCEPROP 2 LAST SIG_NAME SW_PVDDCR_CPU0_P0_BOOT3_RC
J 2
(-3485 5160);
DISPLAY 0.489362 (-3485 5160);
FORCEPROP 2 LASTPROP $XRERR UNIQUE?
J 0
(-3725 5160);
DISPLAY 0.638298 (-3725 5160);
PAINT MONO (-3725 5160);
DISPLAY INVISIBLE (-3725 5160);
WIRE 16 -1 (-5375 1850)(-4475 1850);
FORCEPROP 2 LAST SIG_NAME SW_PVDDCR_CPU0_P0_BOOT4
J 0
(-5260 1860);
DISPLAY 0.489362 (-5260 1860);
FORCEPROP 2 LASTPROP $XRERR UNIQUE?
J 0
(-5500 1860);
DISPLAY 0.638298 (-5500 1860);
PAINT MONO (-5500 1860);
DISPLAY INVISIBLE (-5500 1860);
WIRE 16 -1 (-3400 1850)(-3400 1825);
WIRE 16 -1 (-4275 1850)(-3400 1850);
FORCEPROP 2 LAST SIG_NAME SW_PVDDCR_CPU0_P0_BOOT4_RC
J 2
(-3435 1860);
DISPLAY 0.489362 (-3435 1860);
FORCEPROP 2 LASTPROP $XRERR UNIQUE?
J 0
(-3675 1860);
DISPLAY 0.638298 (-3675 1860);
PAINT MONO (-3675 1860);
DISPLAY INVISIBLE (-3675 1860);
WIRE 16 -1 (-3400 1625)(-3400 1600);
WIRE 16 -1 (-3400 1600)(-5375 1600);
FORCEPROP 2 LAST SIG_NAME SW_PVDDCR_CPU0_P0_PH4
J 0
(-5260 1610);
DISPLAY 0.489362 (-5260 1610);
FORCEPROP 2 LASTPROP $XRERR UNIQUE?
J 0
(-5500 1610);
DISPLAY 0.638298 (-5500 1610);
PAINT MONO (-5500 1610);
DISPLAY INVISIBLE (-5500 1610);
WIRE 16 -1 (-4300 1225)(-4300 975);
FORCEPROP 2 LAST SIG_NAME SW_PVDDCR_CPU0_P0_SW4_RC
J 0
(-4260 1060);
DISPLAY 0.489362 (-4260 1060);
FORCEPROP 2 LASTPROP $XRERR UNIQUE?
J 0
(-4500 1060);
DISPLAY 0.638298 (-4500 1060);
PAINT MONO (-4500 1060);
DISPLAY INVISIBLE (-4500 1060);
WIRE 16 -1 (-3100 1500)(-4300 1500);
WIRE 16 -1 (-4300 1500)(-4300 1425);
WIRE 16 -1 (-5375 1500)(-4300 1500);
FORCEPROP 2 LAST SIG_NAME SW_PVDDCR_CPU0_P0_SW4
J 0
(-5260 1510);
DISPLAY 0.489362 (-5260 1510);
FORCEPROP 2 LASTPROP $XRERR UNIQUE?
J 0
(-5500 1510);
DISPLAY 0.638298 (-5500 1510);
PAINT MONO (-5500 1510);
DISPLAY INVISIBLE (-5500 1510);
WIRE 16 -1 (-2325 4550)(-1900 4550);
FORCEPROP 2 LAST SIG_NAME IND_CPU0_P0_CPL3
J 0
(-2285 4560);
DISPLAY 0.489362 (-2285 4560);
WIRE 16 -1 (-3625 4550)(-3125 4550);
FORCEPROP 2 LAST SIG_NAME IND_CPU0_P0_CPL2
J 0
(-3610 4560);
DISPLAY 0.489362 (-3610 4560);
WIRE 16 -1 (-3525 1250)(-3100 1250);
FORCEPROP 2 LAST SIG_NAME IND_CPU0_P0_CPL3
J 0
(-3510 1260);
DISPLAY 0.489362 (-3510 1260);
WIRE 16 -1 (-4375 4525)(-4375 4250);
FORCEPROP 2 LAST SIG_NAME SW_PVDDCR_CPU0_P0_SW3_RC
J 0
(-4335 4360);
DISPLAY 0.489362 (-4335 4360);
FORCEPROP 2 LASTPROP $XRERR UNIQUE?
J 0
(-4575 4360);
DISPLAY 0.638298 (-4575 4360);
PAINT MONO (-4575 4360);
DISPLAY INVISIBLE (-4575 4360);
WIRE 16 -1 (-5450 4450)(-4925 4450);
FORCEPROP 2 LAST SIG_NAME NC_PVDDCR_CPU0_P0_GL2_3
J 0
(-5335 4460);
DISPLAY 0.489362 (-5335 4460);
FORCEPROP 2 LASTPROP $XRERR UNIQUE?
J 0
(-4895 4450);
DISPLAY 0.638298 (-4895 4450);
PAINT MONO (-4895 4450);
DISPLAY INVISIBLE (-4895 4450);
WIRE 16 -1 (-5450 4500)(-4925 4500);
FORCEPROP 2 LAST SIG_NAME NC_PVDDCR_CPU0_P0_GL1_3
J 0
(-5335 4510);
DISPLAY 0.489362 (-5335 4510);
FORCEPROP 2 LASTPROP $XRERR UNIQUE?
J 0
(-4895 4500);
DISPLAY 0.638298 (-4895 4500);
PAINT MONO (-4895 4500);
DISPLAY INVISIBLE (-4895 4500);
WIRE 16 -1 (-6300 5150)(-6850 5150);
WIRE 16 -1 (-6850 5325)(-6850 5150);
FORCEPROP 2 LAST SIG_NAME PVDDCR_CPU0_P0_VCC3
J 2
(-6385 5160);
DISPLAY 0.489362 (-6385 5160);
FORCEPROP 2 LASTPROP $XRERR UNIQUE?
J 0
(-6625 5160);
DISPLAY 0.638298 (-6625 5160);
PAINT MONO (-6625 5160);
DISPLAY INVISIBLE (-6625 5160);
WIRE 16 -1 (-6850 5150)(-6850 4950);
WIRE 16 -1 (-6850 4950)(-6300 4950);
WIRE 16 -1 (-7350 5325)(-6850 5325);
WIRE 16 -1 (-7350 5550)(-7350 5325);
WIRE 16 -1 (-7350 5325)(-7350 5250);
WIRE 16 -1 (-6300 4200)(-6900 4200);
FORCEPROP 2 LAST SIG_NAME PVDDCR_CPU0_P0_PWM3
J 2
(-6385 4210);
DISPLAY 0.489362 (-6385 4210);
WIRE 16 -1 (-6300 4300)(-6925 4300);
FORCEPROP 2 LAST SIG_NAME PVDDCR_CPU0_P0_TEMP0
J 2
(-6385 4310);
DISPLAY 0.489362 (-6385 4310);
WIRE 16 -1 (-6300 4800)(-6950 4800);
FORCEPROP 2 LAST SIG_NAME PVDDCR_CPU0_P0_IMON3
J 2
(-6385 4810);
DISPLAY 0.489362 (-6385 4810);
WIRE 16 -1 (-6300 4550)(-6750 4550);
FORCEPROP 2 LAST SIG_NAME NC_PVDDCR_CPU0_P0_DNC3
J 2
(-6385 4560);
DISPLAY 0.489362 (-6385 4560);
FORCEPROP 2 LASTPROP $XRERR UNIQUE?
J 0
(-6990 4550);
DISPLAY 0.638298 (-6990 4550);
PAINT MONO (-6990 4550);
DISPLAY INVISIBLE (-6990 4550);
WIRE 16 -1 (-6925 4500)(-6300 4500);
FORCEPROP 2 LAST SIG_NAME PVDDCR_CPU0_P0_LSET3
J 2
(-6385 4510);
DISPLAY 0.489362 (-6385 4510);
FORCEPROP 2 LASTPROP $XRERR UNIQUE?
J 0
(-6625 4510);
DISPLAY 0.638298 (-6625 4510);
PAINT MONO (-6625 4510);
DISPLAY INVISIBLE (-6625 4510);
WIRE 16 -1 (-7850 4700)(-7675 4700);
WIRE 16 -1 (-6300 4700)(-7675 4700);
FORCEPROP 2 LAST SIG_NAME PVDDCR_CPU0_P0_VCCS
J 2
(-6385 4710);
DISPLAY 0.489362 (-6385 4710);
WIRE 16 -1 (-7675 4625)(-7675 4700);
WIRE 16 -1 (-5375 1250)(-4625 1250);
WIRE 16 -1 (-4625 600)(-4625 1250);
WIRE 16 -1 (-3975 600)(-4625 600);
FORCEPROP 2 LAST SIG_NAME PVDDCR_CPU0_P0_VOS4
J 0
(-5260 1275);
DISPLAY 0.489362 (-5260 1275);
FORCEPROP 2 LASTPROP $XRERR UNIQUE?
J 0
(-5500 1275);
DISPLAY 0.638298 (-5500 1275);
PAINT MONO (-5500 1275);
DISPLAY INVISIBLE (-5500 1275);
WIRE 16 -1 (-5375 1200)(-4850 1200);
FORCEPROP 2 LAST SIG_NAME NC_PVDDCR_CPU0_P0_GL1_4
J 0
(-5260 1210);
DISPLAY 0.489362 (-5260 1210);
FORCEPROP 2 LASTPROP $XRERR UNIQUE?
J 0
(-4820 1200);
DISPLAY 0.638298 (-4820 1200);
PAINT MONO (-4820 1200);
DISPLAY INVISIBLE (-4820 1200);
WIRE 16 -1 (-5375 1150)(-4850 1150);
FORCEPROP 2 LAST SIG_NAME NC_PVDDCR_CPU0_P0_GL2_4
J 0
(-5260 1160);
DISPLAY 0.489362 (-5260 1160);
FORCEPROP 2 LASTPROP $XRERR UNIQUE?
J 0
(-4820 1150);
DISPLAY 0.638298 (-4820 1150);
PAINT MONO (-4820 1150);
DISPLAY INVISIBLE (-4820 1150);
WIRE 16 -1 (-7250 2300)(-7250 2025);
WIRE 16 -1 (-7250 2025)(-6800 2025);
WIRE 16 -1 (-7250 2025)(-7250 1950);
WIRE 16 -1 (-6800 2025)(-6800 1850);
FORCEPROP 2 LAST SIG_NAME PVDDCR_CPU0_P0_VCC4
J 2
(-6335 1860);
DISPLAY 0.489362 (-6335 1860);
FORCEPROP 2 LASTPROP $XRERR UNIQUE?
J 0
(-6575 1860);
DISPLAY 0.638298 (-6575 1860);
PAINT MONO (-6575 1860);
DISPLAY INVISIBLE (-6575 1860);
WIRE 16 -1 (-6800 1850)(-6225 1850);
WIRE 16 -1 (-6800 1850)(-6800 1650);
WIRE 16 -1 (-6800 1650)(-6225 1650);
WIRE 16 -1 (-6225 1500)(-6875 1500);
FORCEPROP 2 LAST SIG_NAME PVDDCR_CPU0_P0_IMON4
J 2
(-6285 1510);
DISPLAY 0.489362 (-6285 1510);
WIRE 16 -1 (-6225 1000)(-6850 1000);
FORCEPROP 2 LAST SIG_NAME PVDDCR_CPU0_P0_TEMP0
J 2
(-6285 1010);
DISPLAY 0.489362 (-6285 1010);
WIRE 16 -1 (-6225 1250)(-6675 1250);
FORCEPROP 2 LAST SIG_NAME NC_PVDDCR_CPU0_P0_DNC4
J 2
(-6285 1260);
DISPLAY 0.489362 (-6285 1260);
FORCEPROP 2 LASTPROP $XRERR UNIQUE?
J 0
(-6915 1250);
DISPLAY 0.638298 (-6915 1250);
PAINT MONO (-6915 1250);
DISPLAY INVISIBLE (-6915 1250);
WIRE 16 -1 (-6850 1200)(-6225 1200);
FORCEPROP 2 LAST SIG_NAME PVDDCR_CPU0_P0_LSET4
J 2
(-6285 1210);
DISPLAY 0.489362 (-6285 1210);
FORCEPROP 2 LASTPROP $XRERR UNIQUE?
J 0
(-6525 1210);
DISPLAY 0.638298 (-6525 1210);
PAINT MONO (-6525 1210);
DISPLAY INVISIBLE (-6525 1210);
WIRE 16 -1 (-6225 900)(-6825 900);
FORCEPROP 2 LAST SIG_NAME PVDDCR_CPU0_P0_PWM4
J 2
(-6285 910);
DISPLAY 0.489362 (-6285 910);
WIRE 16 -1 (-7775 1400)(-7600 1400);
WIRE 16 -1 (-6225 1400)(-7600 1400);
FORCEPROP 2 LAST SIG_NAME PVDDCR_CPU0_P0_VCCS
J 2
(-6285 1410);
DISPLAY 0.489362 (-6285 1410);
WIRE 16 -1 (-7600 1325)(-7600 1400);
DOT 1 (-4400 2175);
DOT 1 (-7600 1400);
DOT 1 (-6800 1850);
DOT 1 (-7250 2025);
DOT 1 (-7250 2625);
DOT 1 (-6900 2625);
DOT 1 (-5225 900);
DOT 1 (-5225 950);
DOT 1 (-5225 1000);
DOT 1 (-4300 1500);
DOT 1 (-5275 2150);
DOT 1 (-5100 2575);
DOT 1 (-4725 2175);
DOT 1 (-4725 2575);
DOT 1 (-4075 2175);
DOT 1 (-4400 2575);
DOT 1 (-4075 2575);
DOT 1 (-7675 4700);
DOT 1 (-7350 5325);
DOT 1 (-7350 5875);
DOT 1 (-6850 5150);
DOT 1 (-7000 5875);
DOT 1 (-5300 4250);
DOT 1 (-5300 4200);
DOT 1 (-5300 4300);
DOT 1 (-5350 5450);
DOT 1 (-5225 5875);
DOT 1 (-4375 4800);
DOT 1 (-4550 5875);
DOT 1 (-4225 5475);
DOT 1 (-4225 5875);
DOT 1 (-3700 2175);
DOT 1 (-3700 2575);
DOT 1 (-1500 1500);
DOT 1 (-1300 1500);
DOT 1 (-800 1100);
DOT 1 (-800 1500);
DOT 1 (-3925 5475);
DOT 1 (-3925 5875);
DOT 1 (-1600 4800);
DOT 1 (-975 4400);
DOT 1 (-1400 4800);
DOT 1 (-975 4800);
DOT 1 (-4550 5475);
DOT 1 (-4875 5475);
DOT 1 (-4875 5875);
FORCENOTE
PVDDCR_CPU0_P0_PHASE4
(-6475 2825) 0;
DISPLAY LEFT (-6475 2825);
DISPLAY 1.595745 (-6475 2825);
PAINT WHITE (-6475 2825);
FORCENOTE
PVDDCR_CPU0_P0_PHASE3
(-6450 6200) 0;
DISPLAY LEFT (-6450 6200);
DISPLAY 1.595745 (-6450 6200);
PAINT WHITE (-6450 6200);
FORCENOTE
PGL6303.151HLT
(-2450 1825) 0;
DISPLAY LEFT (-2450 1825);
DISPLAY 0.638298 (-2450 1825);
PAINT WHITE (-2450 1825);
FORCENOTE
ISAT:70A@100C
(-2450 1775) 0;
DISPLAY LEFT (-2450 1775);
DISPLAY 0.638298 (-2450 1775);
PAINT WHITE (-2450 1775);
FORCENOTE
11.0*7.5*12.5
(-2450 1725) 0;
DISPLAY LEFT (-2450 1725);
DISPLAY 0.638298 (-2450 1725);
PAINT WHITE (-2450 1725);
FORCENOTE
2ND=CV+15^0TZ01
(-2450 1575) 0;
DISPLAY LEFT (-2450 1575);
DISPLAY 0.638298 (-2450 1575);
PAINT WHITE (-2450 1575);
FORCENOTE
DCR=1-4,0.105M OHM
(-2450 1675) 0;
DISPLAY LEFT (-2450 1675);
DISPLAY 0.638298 (-2450 1675);
PAINT WHITE (-2450 1675);
FORCENOTE
DCR=2-3,0.27M OHM
(-2450 1625) 0;
DISPLAY LEFT (-2450 1625);
DISPLAY 0.638298 (-2450 1625);
PAINT WHITE (-2450 1625);
FORCENOTE
DCR=2-3,0.27M OHM
(-2475 4925) 0;
DISPLAY LEFT (-2475 4925);
DISPLAY 0.638298 (-2475 4925);
PAINT WHITE (-2475 4925);
FORCENOTE
2ND=CV+15^0TZ01
(-2475 4875) 0;
DISPLAY LEFT (-2475 4875);
DISPLAY 0.638298 (-2475 4875);
PAINT WHITE (-2475 4875);
FORCENOTE
11.0*7.5*12.5
(-2475 5025) 0;
DISPLAY LEFT (-2475 5025);
DISPLAY 0.638298 (-2475 5025);
PAINT WHITE (-2475 5025);
FORCENOTE
ISAT:70A@100C
(-2475 5075) 0;
DISPLAY LEFT (-2475 5075);
DISPLAY 0.638298 (-2475 5075);
PAINT WHITE (-2475 5075);
FORCENOTE
PGL6303.151HLT
(-2475 5125) 0;
DISPLAY LEFT (-2475 5125);
DISPLAY 0.638298 (-2475 5125);
PAINT WHITE (-2475 5125);
FORCENOTE
DCR=1-4,0.105M OHM
(-2475 4975) 0;
DISPLAY LEFT (-2475 4975);
DISPLAY 0.638298 (-2475 4975);
PAINT WHITE (-2475 4975);
QUIT
